# Lightning_PEB_EQL.xlsx — PCIe (si-constraints)
|  | PCIE (Diff Pair 85±10%) |  | W/Sd=5.38/6.2 for outer layout and 5.25/7.5 for inner layer  W:trace width Sd:diff Pair space |  |  |  |  |  |  |  |  |  |  |  |  |  |  |  |  |  |  |  |  |  |  |  |  |  |  |  |  |
| Leopard-BW to Re-timer card |  |  |  |  |  |  |  |  |  |  |  |  |  |  |  |  |  |  |  |  |  |  |  |  |  |  |  |  |  |  |  |
| Leopard-BW |  |  |  |  |  |  |  |  | Leopard-BW Raise Card |  |  |  |  | Re-timer Card |  |  |  |  |  |  |  |  |  |  |  |  |  |  |  |  |  |
| Net Name | PKG Lengths | PCB Net Length | Differential Match | Net Name | PCB Net Length | Differential Match | MB Total Length | Differential Match | Net Name | PCB Net Length | Differential Match | MB to Raise Card Total Length | Differential Match | Net Name | PKG Lengths | PCB Net Length | Re-timer Total Length | Differential Match | Leopard to Re-timer Total Length | Differential Match | In spec? |  |  |  |  |  |  |  |  |  |  |
| P3E_CPU0_PE2_RISER1_TX_DP_0 |  | 10551.21 |  | P3E_CPU0_PE2_RISER1_TX_C_DP_0 | 268.56 |  | 10819.769999999999 |  | PCIE_SLOT1_TXP0 | 3972 |  | 14791.769999999999 |  | D85_LEOPARD_PCIE_TX_DP0 | 329.51 | 1830.8 | 2160.31 |  | 16952.079999999998 |  | yes; within 19 inch |  |  |  |  |  |  |  |  |  |  |
| P3E_CPU0_PE2_RISER1_TX_DN_0 |  | 10550.18 | yes; within 5 mils | P3E_CPU0_PE2_RISER1_TX_C_DN_0 | 268.52999999999997 | yes; within 5 mils | 10818.710000000001 | yes; within 5 mils | PCIE_SLOT1_TXN0 | 3972.08 | yes; within 1 mils | 14790.79 | yes; within 5 mils | D85_LEOPARD_PCIE_TX_DN0 | 333 | 1826.44 | 2159.44 | yes; within 1 mils | 16950.23 | yes; within 5 mils | yes; within 19 inch |  |  |  |  |  |  |  |  |  |  |
| P3E_CPU0_PE2_RISER1_TX_DP_1 |  | 10424.09 |  | P3E_CPU0_PE2_RISER1_TX_C_DP_1 | 253.94 |  | 10678.03 |  | PCIE_SLOT1_TXP1 | 3807.17 |  | 14485.2 |  | D85_LEOPARD_PCIE_TX_DP1 | 309.35000000000002 | 1790.79 | 2100.14 |  | 16585.34 |  | yes; within 19 inch |  |  |  |  |  |  |  |  |  |  |
| P3E_CPU0_PE2_RISER1_TX_DN_1 |  | 10422.43 | yes; within 5 mils | P3E_CPU0_PE2_RISER1_TX_C_DN_1 | 252.65 | yes; within 5 mils | 10675.08 | yes; within 5 mils | PCIE_SLOT1_TXN1 | 3806.2 | yes; within 1 mils | 14481.279999999999 | yes; within 5 mils | D85_LEOPARD_PCIE_TX_DN1 | 312.85000000000002 | 1788.25 | 2101.1 | yes; within 1 mils | 16582.379999999997 | yes; within 5 mils | yes; within 19 inch |  |  |  |  |  |  |  |  |  |  |
|  | routing bundle delta | 128.77999999999884 | yes; within 500mil | routing bundle delta | 15.909999999999997 | yes; within 500mil | 144.68999999999869 | yes; within 500mil | routing bundle delta | 165.88000000000011 | yes; within 200mil | 310.48999999999978 | yes; within 500mil |  |  | routing bundle delta | 60.170000000000073 | yes; within 100mil | 369.70000000000073 | yes; within 500mil |  |  |  |  |  |  |  |  |  |  |  |
| P3E_CPU0_PE2_RISER1_TX_DP_2 |  | 10249.56 |  | P3E_CPU0_PE2_RISER1_TX_C_DP_2 | 254.03 |  | 10503.59 |  | PCIE_SLOT1_TXP2 | 3688.53 |  | 14192.12 |  | D85_LEOPARD_PCIE_TX_DP2 | 279.39999999999998 | 1794.53 | 2073.9299999999998 |  | 16266.050000000001 |  | yes; within 19 inch |  |  |  |  |  |  |  |  |  |  |
| P3E_CPU0_PE2_RISER1_TX_DN_2 |  | 10251.459999999999 | yes; within 5 mils | P3E_CPU0_PE2_RISER1_TX_C_DN_2 | 252.77 | yes; within 5 mils | 10504.23 | yes; within 5 mils | PCIE_SLOT1_TXN2 | 3688.05 | yes; within 1 mils | 14192.279999999999 | yes; within 5 mils | D85_LEOPARD_PCIE_TX_DN2 | 282.83 | 1791.98 | 2074.81 | yes; within 1 mils | 16267.089999999998 | yes; within 5 mils | yes; within 19 inch |  |  |  |  |  |  |  |  |  |  |
| P3E_CPU0_PE2_RISER1_TX_DP_3 |  | 10036.02 |  | P3E_CPU0_PE2_RISER1_TX_C_DP_3 | 253.94 |  | 10289.960000000001 |  | PCIE_SLOT1_TXP3 | 3628.79 |  | 13918.75 |  | D85_LEOPARD_PCIE_TX_DP3 | 257.04000000000002 | 1801.69 | 2058.73 |  | 15977.48 |  | yes; within 19 inch |  |  |  |  |  |  |  |  |  |  |
| P3E_CPU0_PE2_RISER1_TX_DN_3 |  | 10036.32 | yes; within 5 mils | P3E_CPU0_PE2_RISER1_TX_C_DN_3 | 252.77 | yes; within 5 mils | 10289.09 | yes; within 5 mils | PCIE_SLOT1_TXN3 | 3628.42 | yes; within 1 mils | 13917.51 | yes; within 5 mils | D85_LEOPARD_PCIE_TX_DN3 | 260.62 | 1798.82 | 2059.44 | yes; within 1 mils | 15976.95 | yes; within 5 mils | yes; within 19 inch |  |  |  |  |  |  |  |  |  |  |
|  | routing bundle delta | 215.43999999999869 | yes; within 500mil | routing bundle delta | 1.2599999999999909 | yes; within 500mil | 215.13999999999942 | yes; within 500mil | routing bundle delta | 60.110000000000127 | yes; within 200mil | 274.76999999999862 | yes; within 500mil |  |  | routing bundle delta | 16.079999999999927 | yes; within 100mil | 290.1399999999976 | yes; within 500mil |  |  |  |  |  |  |  |  |  |  |  |
| P3E_CPU0_PE2_RISER1_TX_DP_4 |  | 9941.1 |  | P3E_CPU0_PE2_RISER1_TX_C_DP_4 | 253.94 |  | 10195.040000000001 |  | PCIE_SLOT1_TXP4 | 3479.79 |  | 13674.830000000002 |  | D85_LEOPARD_PCIE_TX_DP4 | 235.63 | 1814.02 | 2049.65 |  | 15724.480000000001 |  | yes; within 19 inch |  |  |  |  |  |  |  |  |  |  |
| P3E_CPU0_PE2_RISER1_TX_DN_4 |  | 9944.8700000000008 | yes; within 5 mils | P3E_CPU0_PE2_RISER1_TX_C_DN_4 | 252.77 | yes; within 5 mils | 10197.640000000001 | yes; within 5 mils | PCIE_SLOT1_TXN4 | 3478.84 | yes; within 1 mils | 13676.480000000001 | yes; within 5 mils | D85_LEOPARD_PCIE_TX_DN4 | 239.05 | 1809.68 | 2048.73 | yes; within 1 mils | 15725.210000000001 | yes; within 5 mils | yes; within 19 inch |  |  |  |  |  |  |  |  |  |  |
| P3E_CPU0_PE2_RISER1_TX_DP_5 |  | 9777 |  | P3E_CPU0_PE2_RISER1_TX_C_DP_5 | 253.94 |  | 10030.94 |  | PCIE_SLOT1_TXP5 | 3423.88 |  | 13454.82 |  | D85_LEOPARD_PCIE_TX_DP5 | 218.24 | 1830.93 | 2049.17 |  | 15503.99 |  | yes; within 19 inch |  |  |  |  |  |  |  |  |  |  |
| P3E_CPU0_PE2_RISER1_TX_DN_5 |  | 9779.2900000000009 | yes; within 5 mils | P3E_CPU0_PE2_RISER1_TX_C_DN_5 | 252.77 | yes; within 5 mils | 10032.060000000001 | yes; within 5 mils | PCIE_SLOT1_TXN5 | 3423.43 | yes; within 1 mils | 13455.490000000002 | yes; within 5 mils | D85_LEOPARD_PCIE_TX_DN5 | 221.82 | 1826.46 | 2048.2800000000002 | yes; within 1 mils | 15503.770000000002 | yes; within 5 mils | yes; within 19 inch |  |  |  |  |  |  |  |  |  |  |
|  | routing bundle delta | 167.8700000000008 | yes; within 500mil | routing bundle delta | 1.1699999999999875 | yes; within 500mil | 166.70000000000073 | yes; within 500mil | routing bundle delta | 56.360000000000127 | yes; within 200mil | 221.66000000000167 | yes; within 500mil |  |  | routing bundle delta | 1.3699999999998909 | yes; within 100mil | 221.43999999999869 | yes; within 500mil |  |  |  |  |  |  |  |  |  |  |  |
| P3E_CPU0_PE2_RISER1_TX_DP_6 |  | 9997.0300000000007 |  | P3E_CPU0_PE2_RISER1_TX_C_DP_6 | 253.94 |  | 10250.970000000001 |  | PCIE_SLOT1_TXP6 | 3291.3 |  | 13542.27 |  | D85_LEOPARD_PCIE_TX_DP6 | 210.54 | 1862.52 | 2073.06 |  | 15615.33 |  | yes; within 19 inch |  |  |  |  |  |  |  |  |  |  |
| P3E_CPU0_PE2_RISER1_TX_DN_6 |  | 9998.32 | yes; within 5 mils | P3E_CPU0_PE2_RISER1_TX_C_DN_6 | 252.77 | yes; within 5 mils | 10251.09 | yes; within 5 mils | PCIE_SLOT1_TXN6 | 3291.32 | yes; within 1 mils | 13542.41 | yes; within 5 mils | D85_LEOPARD_PCIE_TX_DN6 | 213.96 | 1860.01 | 2073.9699999999998 | yes; within 1 mils | 15616.38 | yes; within 5 mils | yes; within 19 inch |  |  |  |  |  |  |  |  |  |  |
| P3E_CPU0_PE2_RISER1_TX_DP_7 |  | 9807.2099999999991 |  | P3E_CPU0_PE2_RISER1_TX_C_DP_7 | 253.94 |  | 10061.15 |  | PCIE_SLOT1_TXP7 | 3192.23 |  | 13253.38 |  | D85_LEOPARD_PCIE_TX_DP7 | 193.86 | 1899.8 | 2093.66 |  | 15347.039999999999 |  | yes; within 19 inch |  |  |  |  |  |  |  |  |  |  |
| P3E_CPU0_PE2_RISER1_TX_DN_7 |  | 9805.31 | yes; within 5 mils | P3E_CPU0_PE2_RISER1_TX_C_DN_7 | 252.77 | yes; within 5 mils | 10058.08 | yes; within 5 mils | PCIE_SLOT1_TXN7 | 3191.29 | yes; within 1 mils | 13249.369999999999 | yes; within 5 mils | D85_LEOPARD_PCIE_TX_DN7 | 197.28 | 1897.27 | 2094.5500000000002 | yes; within 1 mils | 15343.919999999998 | yes; within 5 mils | yes; within 19 inch |  |  |  |  |  |  |  |  |  |  |
|  | routing bundle delta | 193.01000000000022 | yes; within 500mil | routing bundle delta | 1.1699999999999875 | yes; within 500mil | 193.01000000000022 | yes; within 500mil | routing bundle delta | 100.0300000000002 | yes; within 200mil | 293.04000000000087 | yes; within 500mil |  |  | routing bundle delta | 21.490000000000236 | yes; within 100mil | 272.46000000000095 | yes; within 500mil |  |  |  |  |  |  |  |  |  |  |  |
| P3E_CPU0_PE2_RISER1_TX_DP_8 |  | 9640.0400000000009 |  | P3E_CPU0_PE2_RISER1_TX_C_DP_8 | 312.41000000000003 |  | 9952.4500000000007 |  | PCIE_SLOT1_TXP8 | 3129.06 |  | 13081.51 |  | D85_LEOPARD_PCIE_TX_DP8 | 195.37 | 1988.17 | 2183.54 |  | 15265.05 |  | yes; within 19 inch |  |  |  |  |  |  |  |  |  |  |
| P3E_CPU0_PE2_RISER1_TX_DN_8 |  | 9642.02 | yes; within 5 mils | P3E_CPU0_PE2_RISER1_TX_C_DN_8 | 313.33999999999997 | yes; within 5 mils | 9955.36 | yes; within 5 mils | PCIE_SLOT1_TXN8 | 3129.09 | yes; within 1 mils | 13084.45 | yes; within 5 mils | D85_LEOPARD_PCIE_TX_DN8 | 199.31 | 1983.8 | 2183.11 | yes; within 1 mils | 15267.560000000001 | yes; within 5 mils | yes; within 19 inch |  |  |  |  |  |  |  |  |  |  |
| P3E_CPU0_PE2_RISER1_TX_DP_9 |  | 9612.2900000000009 |  | P3E_CPU0_PE2_RISER1_TX_C_DP_9 | 317.42 |  | 9929.7100000000009 |  | PCIE_SLOT1_TXP9 | 3057.79 |  | 12987.5 |  | D85_LEOPARD_PCIE_TX_DP9 | 206.65 | 2052.1799999999998 | 2258.83 |  | 15246.33 |  | yes; within 19 inch |  |  |  |  |  |  |  |  |  |  |
| P3E_CPU0_PE2_RISER1_TX_DN_9 |  | 9610.2900000000009 | yes; within 5 mils | P3E_CPU0_PE2_RISER1_TX_C_DN_9 | 316.13 | yes; within 5 mils | 9926.42 | yes; within 5 mils | PCIE_SLOT1_TXN9 | 3058.39 | yes; within 1 mils | 12984.81 | yes; within 5 mils | D85_LEOPARD_PCIE_TX_DN9 | 210.06 | 2048.61 | 2258.67 | yes; within 1 mils | 15243.48 | yes; within 5 mils | yes; within 19 inch |  |  |  |  |  |  |  |  |  |  |
|  | routing bundle delta | 31.729999999999563 | yes; within 500mil | routing bundle delta | 5.0099999999999909 | yes; within 500mil | 28.940000000000509 | yes; within 500mil | routing bundle delta | 71.300000000000182 | yes; within 200mil | 99.640000000001237 | yes; within 500mil |  |  | routing bundle delta | 75.7199999999998 | yes; within 100mil | 24.080000000001746 | yes; within 500mil |  |  |  |  |  |  |  |  |  |  |  |
| P3E_CPU0_PE2_RISER1_TX_DP_10 |  | 9515.2900000000009 |  | P3E_CPU0_PE2_RISER1_TX_C_DP_10 | 314.73 |  | 9830.02 |  | PCIE_SLOT1_TXP10 | 2996.36 |  | 12826.380000000001 |  | D85_LEOPARD_PCIE_TX_DP10 | 215.82 | 2219.1799999999998 | 2435 |  | 15261.380000000001 |  | yes; within 19 inch |  |  |  |  |  |  |  |  |  |  |
| P3E_CPU0_PE2_RISER1_TX_DN_10 |  | 9514.51 | yes; within 5 mils | P3E_CPU0_PE2_RISER1_TX_C_DN_10 | 313.55 | yes; within 5 mils | 9828.06 | yes; within 5 mils | PCIE_SLOT1_TXN10 | 2997.3 | yes; within 1 mils | 12825.36 | yes; within 5 mils | D85_LEOPARD_PCIE_TX_DN10 | 219.24 | 2215.62 | 2434.8599999999997 | yes; within 1 mils | 15260.220000000001 | yes; within 5 mils | yes; within 19 inch |  |  |  |  |  |  |  |  |  |  |
| P3E_CPU0_PE2_RISER1_TX_DP_11 |  | 9644.6200000000008 |  | P3E_CPU0_PE2_RISER1_TX_C_DP_11 | 325.89 |  | 9970.51 |  | PCIE_SLOT1_TXP11 | 2956.5 |  | 12927.01 |  | D85_LEOPARD_PCIE_TX_DP11 | 233.93 | 2290.7800000000002 | 2524.71 |  | 15451.720000000001 |  | yes; within 19 inch |  |  |  |  |  |  |  |  |  |  |
| P3E_CPU0_PE2_RISER1_TX_DN_11 |  | 9641.61 | yes; within 5 mils | P3E_CPU0_PE2_RISER1_TX_C_DN_11 | 325.07 | yes; within 5 mils | 9966.68 | yes; within 5 mils | PCIE_SLOT1_TXN11 | 2957.31 | yes; within 1 mils | 12923.99 | yes; within 5 mils | D85_LEOPARD_PCIE_TX_DN11 | 237.35 | 2286.85 | 2524.1999999999998 | yes; within 1 mils | 15448.189999999999 | yes; within 5 mils | yes; within 19 inch |  |  |  |  |  |  |  |  |  |  |
|  | routing bundle delta | 130.11000000000058 | yes; within 500mil | routing bundle delta | 12.339999999999975 | yes; within 500mil | 142.45000000000073 | yes; within 500mil | routing bundle delta | 40.800000000000182 | yes; within 200mil | 101.64999999999964 | yes; within 500mil |  |  | routing bundle delta | 89.850000000000364 | yes; within 100mil | 191.5 | yes; within 500mil |  |  |  |  |  |  |  |  |  |  |  |
| P3E_CPU0_PE2_RISER1_TX_DP_12 |  | 9711.64 |  | P3E_CPU0_PE2_RISER1_TX_C_DP_12 | 320.87 |  | 10032.51 |  | PCIE_SLOT1_TXP12 | 2938.85 |  | 12971.36 |  | D85_LEOPARD_PCIE_TX_DP12 | 249.55 | 2481.14 | 2730.69 |  | 15702.050000000001 |  | yes; within 19 inch |  |  |  |  |  |  |  |  |  |  |
| P3E_CPU0_PE2_RISER1_TX_DN_12 |  | 9708.8700000000008 | yes; within 5 mils | P3E_CPU0_PE2_RISER1_TX_C_DN_12 | 318.8 | yes; within 5 mils | 10027.67 | yes; within 5 mils | PCIE_SLOT1_TXN12 | 2939.76 | yes; within 1 mils | 12967.43 | yes; within 5 mils | D85_LEOPARD_PCIE_TX_DN12 | 252.97 | 2478.3200000000002 | 2731.29 | yes; within 1 mils | 15698.720000000001 | yes; within 5 mils | yes; within 19 inch |  |  |  |  |  |  |  |  |  |  |
| P3E_CPU0_PE2_RISER1_TX_DP_13 |  | 9833.4500000000007 |  | P3E_CPU0_PE2_RISER1_TX_C_DP_13 | 315.08 |  | 10148.530000000001 |  | PCIE_SLOT1_TXP13 | 2938.6 |  | 13087.130000000001 |  | D85_LEOPARD_PCIE_TX_DP13 | 271.10000000000002 | 2558.33 | 2829.43 |  | 15916.560000000001 |  | yes; within 19 inch |  |  |  |  |  |  |  |  |  |  |
| P3E_CPU0_PE2_RISER1_TX_DN_13 |  | 9835.18 | yes; within 5 mils | P3E_CPU0_PE2_RISER1_TX_C_DN_13 | 313.62 | yes; within 5 mils | 10148.800000000001 | yes; within 5 mils | PCIE_SLOT1_TXN13 | 2939.18 | yes; within 1 mils | 13087.980000000001 | yes; within 5 mils | D85_LEOPARD_PCIE_TX_DN13 | 274.72000000000003 | 2554.4499999999998 | 2829.17 | yes; within 1 mils | 15917.150000000001 | yes; within 5 mils | yes; within 19 inch |  |  |  |  |  |  |  |  |  |  |
|  | routing bundle delta | 126.30999999999949 | yes; within 500mil | routing bundle delta | 7.25 | yes; within 500mil | 121.13000000000102 | yes; within 500mil | routing bundle delta | 1.1600000000003092 | yes; within 200mil | 120.55000000000109 | yes; within 500mil |  |  | routing bundle delta | 98.739999999999782 | yes; within 100mil | 218.43000000000029 | yes; within 500mil |  |  |  |  |  |  |  |  |  |  |  |
| P3E_CPU0_PE2_RISER1_TX_DP_14 |  | 9696.1299999999992 |  | P3E_CPU0_PE2_RISER1_TX_C_DP_14 | 288.32 |  | 9984.4499999999989 |  | PCIE_SLOT1_TXP14 | 2946.58 |  | 12931.029999999999 |  | D85_LEOPARD_PCIE_TX_DP14 | 293.89999999999998 | 2703.81 | 2997.71 |  | 15928.739999999998 |  | yes; within 19 inch |  |  |  |  |  |  |  |  |  |  |
| P3E_CPU0_PE2_RISER1_TX_DN_14 |  | 9696.81 | yes; within 5 mils | P3E_CPU0_PE2_RISER1_TX_C_DN_14 | 290.05 | yes; within 5 mils | 9986.8599999999988 | yes; within 5 mils | PCIE_SLOT1_TXN14 | 2947.56 | yes; within 1 mils | 12934.419999999998 | yes; within 5 mils | D85_LEOPARD_PCIE_TX_DN14 | 297.32 | 2701.32 | 2998.6400000000003 | yes; within 1 mils | 15933.059999999998 | yes; within 5 mils | yes; within 19 inch |  |  |  |  |  |  |  |  |  |  |
| P3E_CPU0_PE2_RISER1_TX_DP_15 |  | 9701.09 |  | P3E_CPU0_PE2_RISER1_TX_C_DP_15 | 344.31 |  | 10045.4 |  | PCIE_SLOT1_TXP15 | 2987.64 |  | 13033.039999999999 |  | D85_LEOPARD_PCIE_TX_DP15 | 323.06 | 2771.47 | 3094.5299999999997 |  | 16127.57 |  | yes; within 19 inch |  |  |  |  |  |  |  |  |  |  |
| P3E_CPU0_PE2_RISER1_TX_DN_15 |  | 9698.77 | yes; within 5 mils | P3E_CPU0_PE2_RISER1_TX_C_DN_15 | 346.81 | yes; within 5 mils | 10045.58 | yes; within 5 mils | PCIE_SLOT1_TXN15 | 2988.58 | yes; within 1 mils | 13034.16 | yes; within 5 mils | D85_LEOPARD_PCIE_TX_DN15 | 326.47000000000003 | 2767.87 | 3094.34 | yes; within 1 mils | 16128.5 | yes; within 5 mils | yes; within 19 inch |  |  |  |  |  |  |  |  |  |  |
|  | routing bundle delta | 4.9600000000009459 | yes; within 500mil | routing bundle delta | 58.490000000000009 | yes; within 500mil | 61.130000000001019 | yes; within 500mil | routing bundle delta | 42 | yes; within 200mil | 103.13000000000102 | yes; within 500mil |  |  | routing bundle delta | 96.819999999999709 | yes; within 100mil | 199.76000000000204 | yes; within 500mil |  |  |  |  |  |  |  |  |  |  |  |
|  | diff pair to pair delta | 1036.6999999999989 | yes; within 7000mil | diff pair to pair delta | 94.16 | yes; within 7000mil | 991.70999999999913 | yes; within 7000mil | diff pair to pair delta | 1033.48 | yes; within 2000mil | 1966.409999999998 | yes; within 7000mil |  |  | diff pair to pair delta | 1046.2499999999995 | yes; within 2000mil | 1708.5999999999985 | yes; within 9000mil |  |  |  |  |  |  |  |  |  |  |  |
| Leopard-BW |  |  |  |  |  | Leopard-BW Raise Card |  |  |  |  | Re-timer Card |  |  |  |  |  |  |  |  |  |  |  |  |  |  |  |  |  |  |  |  |
| Net Name | PKG Lengths | PCB Net Length | Differential Match | MB Total Length | Differential Match | Net Name | PCB Net Length | Differential Match | MB to Raise Card Total Length | Differential Match | Net Name | PCB Net Length | Differential Match | Net Name | PKG Lengths | PCB Net Length | Re-timer Total Length | Differential Match | Total Length | Differential Match | In spec? |  |  |  |  |  |  |  |  |  |  |
| P3E_CPU0_PE2_RISER1_RX_DP_0 |  | 10759.68 |  | 10759.68 |  | PCIE_SLOT1_RXP0 | 3975.79 |  | 14735.470000000001 |  | D85_LEOPARD_PCIE_RX_DP0 | 651.64 |  | D85_LEOPARD_PCIE_RX_C_DP0 | 293.24 | 1274.67 | 2219.5500000000002 |  | 16955.02 |  | yes; within 19 inch |  |  |  |  |  |  |  |  |  |  |
| P3E_CPU0_PE2_RISER1_RX_DN_0 |  | 10758.23 | yes; within 5 mils | 10758.23 | yes; within 5 mils | PCIE_SLOT1_RXN0 | 3974.95 | yes; within 1 mils | 14733.18 | yes; within 5 mils | D85_LEOPARD_PCIE_RX_DN0 | 652.20000000000005 | yes; within 1 mils | D85_LEOPARD_PCIE_RX_C_DN0 | 293.24 | 1274.6300000000001 | 2220.0700000000002 | yes; within 1 mils | 16953.25 | yes; within 5 mils | yes; within 19 inch |  |  |  |  |  |  |  |  |  |  |
| P3E_CPU0_PE2_RISER1_RX_DP_1 |  | 10853.67 |  | 10853.67 |  | PCIE_SLOT1_RXP1 | 3822.81 |  | 14676.48 |  | D85_LEOPARD_PCIE_RX_DP1 | 689.08 |  | D85_LEOPARD_PCIE_RX_C_DP1 | 255.12 | 1208.02 | 2152.2199999999998 |  | 16828.7 |  | yes; within 19 inch |  |  |  |  |  |  |  |  |  |  |
| P3E_CPU0_PE2_RISER1_RX_DN_1 |  | 10854.15 | yes; within 5 mils | 10854.15 | yes; within 5 mils | PCIE_SLOT1_RXN1 | 3823.75 | yes; within 1 mils | 14677.9 | yes; within 5 mils | D85_LEOPARD_PCIE_RX_DN1 | 688.38 | yes; within 1 mils | D85_LEOPARD_PCIE_RX_C_DN1 | 258.27 | 1205.58 | 2152.23 | yes; within 1 mils | 16830.13 | yes; within 5 mils | yes; within 19 inch |  |  |  |  |  |  |  |  |  |  |
|  | routing bundle delta | 95.920000000000073 | yes; within 500mil | 95.920000000000073 | yes; within 500mil | routing bundle delta | 152.98000000000002 | yes; within 200mil | 58.990000000001601 | yes; within 500mil | routing bundle delta | 37.440000000000055 | yes; within 100mil |  |  | routing bundle delta | 67.850000000000364 | yes; within 100mil | 126.31999999999971 | yes; within 500mil |  |  |  |  |  |  |  |  |  |  |  |
| P3E_CPU0_PE2_RISER1_RX_DP_2 |  | 10749.06 |  | 10749.06 |  | PCIE_SLOT1_RXP2 | 3740.33 |  | 14489.39 |  | D85_LEOPARD_PCIE_RX_DP2 | 702.95 |  | D85_LEOPARD_PCIE_RX_C_DP2 | 229.01 | 1237.3499999999999 | 2169.31 |  | 16658.7 |  | yes; within 19 inch |  |  |  |  |  |  |  |  |  |  |
| P3E_CPU0_PE2_RISER1_RX_DN_2 |  | 10749.32 | yes; within 5 mils | 10749.32 | yes; within 5 mils | PCIE_SLOT1_RXN2 | 3741.1 | yes; within 1 mils | 14490.42 | yes; within 5 mils | D85_LEOPARD_PCIE_RX_DN2 | 702.31 | yes; within 1 mils | D85_LEOPARD_PCIE_RX_C_DN2 | 230.64 | 1236.52 | 2169.4699999999998 | yes; within 1 mils | 16659.89 | yes; within 5 mils | yes; within 19 inch |  |  |  |  |  |  |  |  |  |  |
| P3E_CPU0_PE2_RISER1_RX_DP_3 |  | 10825.84 |  | 10825.84 |  | PCIE_SLOT1_RXP3 | 3666.1 |  | 14491.94 |  | D85_LEOPARD_PCIE_RX_DP3 | 634.73 |  | D85_LEOPARD_PCIE_RX_C_DP3 | 196.1 | 1343.97 | 2174.8000000000002 |  | 16666.740000000002 |  | yes; within 19 inch |  |  |  |  |  |  |  |  |  |  |
| P3E_CPU0_PE2_RISER1_RX_DN_3 |  | 10828.8 | yes; within 5 mils | 10828.8 | yes; within 5 mils | PCIE_SLOT1_RXN3 | 3667.05 | yes; within 1 mils | 14495.849999999999 | yes; within 5 mils | D85_LEOPARD_PCIE_RX_DN3 | 633.83000000000004 | yes; within 1 mils | D85_LEOPARD_PCIE_RX_C_DN3 | 199.13 | 1341.3 | 2174.2599999999998 | yes; within 1 mils | 16670.109999999997 | yes; within 5 mils | yes; within 19 inch |  |  |  |  |  |  |  |  |  |  |
|  | routing bundle delta | 79.739999999999782 | yes; within 500mil | 79.739999999999782 | yes; within 500mil | routing bundle delta | 75 | yes; within 200mil | 6.4599999999991269 | yes; within 500mil | routing bundle delta | 69.12 | yes; within 100mil |  |  | routing bundle delta | 5.4900000000002365 | yes; within 100mil | 11.409999999996217 | yes; within 500mil |  |  |  |  |  |  |  |  |  |  |  |
| P3E_CPU0_PE2_RISER1_RX_DP_4 |  | 10872.57 |  | 10872.57 |  | PCIE_SLOT1_RXP4 | 3498.86 |  | 14371.43 |  | D85_LEOPARD_PCIE_RX_DP4 | 651.04999999999995 |  | D85_LEOPARD_PCIE_RX_C_DP4 | 163.44 | 1347.49 | 2161.98 |  | 16533.41 |  | yes; within 19 inch |  |  |  |  |  |  |  |  |  |  |
| P3E_CPU0_PE2_RISER1_RX_DN_4 |  | 10871.86 | yes; within 5 mils | 10871.86 | yes; within 5 mils | PCIE_SLOT1_RXN4 | 3499.05 | yes; within 1 mils | 14370.91 | yes; within 5 mils | D85_LEOPARD_PCIE_RX_DN4 | 651.09 | yes; within 1 mils | D85_LEOPARD_PCIE_RX_C_DN4 | 166.42 | 1344.59 | 2162.1 | yes; within 1 mils | 16533.009999999998 | yes; within 5 mils | yes; within 19 inch |  |  |  |  |  |  |  |  |  |  |
| P3E_CPU0_PE2_RISER1_RX_DP_5 |  | 10827 |  | 10827 |  | PCIE_SLOT1_RXP5 | 3399.85 |  | 14226.85 |  | D85_LEOPARD_PCIE_RX_DP5 | 603.75 |  | D85_LEOPARD_PCIE_RX_C_DP5 | 133.75 | 1410.41 | 2147.91 |  | 16374.76 |  | yes; within 19 inch |  |  |  |  |  |  |  |  |  |  |
| P3E_CPU0_PE2_RISER1_RX_DN_5 |  | 10825.45 | yes; within 5 mils | 10825.45 | yes; within 5 mils | PCIE_SLOT1_RXN5 | 3400.12 | yes; within 1 mils | 14225.57 | yes; within 5 mils | D85_LEOPARD_PCIE_RX_DN5 | 603.88 | yes; within 1 mils | D85_LEOPARD_PCIE_RX_C_DN5 | 136.91999999999999 | 1406.89 | 2147.69 | yes; within 1 mils | 16373.26 | yes; within 5 mils | yes; within 19 inch |  |  |  |  |  |  |  |  |  |  |
|  | routing bundle delta | 47.119999999998981 | yes; within 500mil | 47.119999999998981 | yes; within 500mil | routing bundle delta | 99.200000000000273 | yes; within 200mil | 145.86000000000058 | yes; within 500mil | routing bundle delta | 47.340000000000032 | yes; within 100mil |  |  | routing bundle delta | 14.409999999999854 | yes; within 100mil | 160.14999999999964 | yes; within 500mil |  |  |  |  |  |  |  |  |  |  |  |
| P3E_CPU0_PE2_RISER1_RX_DP_6 |  | 10872.97 |  | 10872.97 |  | PCIE_SLOT1_RXP6 | 3311.68 |  | 14184.65 |  | D85_LEOPARD_PCIE_RX_DP6 | 544.29999999999995 |  | D85_LEOPARD_PCIE_RX_C_DP6 | 109.44 | 1500.32 | 2154.06 |  | 16338.71 |  | yes; within 19 inch |  |  |  |  |  |  |  |  |  |  |
| P3E_CPU0_PE2_RISER1_RX_DN_6 |  | 10874.12 | yes; within 5 mils | 10874.12 | yes; within 5 mils | PCIE_SLOT1_RXN6 | 3311.77 | yes; within 1 mils | 14185.890000000001 | yes; within 5 mils | D85_LEOPARD_PCIE_RX_DN6 | 543.98 | yes; within 1 mils | D85_LEOPARD_PCIE_RX_C_DN6 | 112.62 | 1497.6 | 2154.1999999999998 | yes; within 1 mils | 16340.09 | yes; within 5 mils | yes; within 19 inch |  |  |  |  |  |  |  |  |  |  |
| P3E_CPU0_PE2_RISER1_RX_DP_7 |  | 10744.43 |  | 10744.43 |  | PCIE_SLOT1_RXP7 | 3224.11 |  | 13968.54 |  | D85_LEOPARD_PCIE_RX_DP7 | 519.82000000000005 |  | D85_LEOPARD_PCIE_RX_C_DP7 | 101.54 | 1582.46 | 2203.8200000000002 |  | 16172.36 |  | yes; within 19 inch |  |  |  |  |  |  |  |  |  |  |
| P3E_CPU0_PE2_RISER1_RX_DN_7 |  | 10742.17 | yes; within 5 mils | 10742.17 | yes; within 5 mils | PCIE_SLOT1_RXN7 | 3223.97 | yes; within 1 mils | 13966.14 | yes; within 5 mils | D85_LEOPARD_PCIE_RX_DN7 | 519.78 | yes; within 1 mils | D85_LEOPARD_PCIE_RX_C_DN7 | 104.72 | 1579.47 | 2203.9700000000003 | yes; within 1 mils | 16170.11 | yes; within 5 mils | yes; within 19 inch |  |  |  |  |  |  |  |  |  |  |
|  | routing bundle delta | 131.95000000000073 | yes; within 500mil | 131.95000000000073 | yes; within 500mil | routing bundle delta | 87.800000000000182 | yes; within 200mil | 219.75000000000182 | yes; within 500mil | routing bundle delta | 24.519999999999982 | yes; within 100mil |  |  | routing bundle delta | 49.910000000000309 | yes; within 100mil | 169.97999999999956 | yes; within 500mil |  |  |  |  |  |  |  |  |  |  |  |
| P3E_CPU0_PE2_RISER1_RX_DP_8 |  | 10833.16 |  | 10833.16 |  | PCIE_SLOT1_RXP8 | 3179.11 |  | 14012.27 |  | D85_LEOPARD_PCIE_RX_DP8 | 476.55 |  | D85_LEOPARD_PCIE_RX_C_DP8 | 102.46 | 1683.87 | 2262.88 |  | 16275.150000000001 |  | yes; within 19 inch |  |  |  |  |  |  |  |  |  |  |
| P3E_CPU0_PE2_RISER1_RX_DN_8 |  | 10829.83 | yes; within 5 mils | 10829.83 | yes; within 5 mils | PCIE_SLOT1_RXN8 | 3179.37 | yes; within 1 mils | 14009.2 | yes; within 5 mils | D85_LEOPARD_PCIE_RX_DN8 | 476.28 | yes; within 1 mils | D85_LEOPARD_PCIE_RX_C_DN8 | 105.59 | 1681.32 | 2263.1899999999996 | yes; within 1 mils | 16272.39 | yes; within 5 mils | yes; within 19 inch |  |  |  |  |  |  |  |  |  |  |
| P3E_CPU0_PE2_RISER1_RX_DP_9 |  | 10737.11 |  | 10737.11 |  | PCIE_SLOT1_RXP9 | 3147.85 |  | 13884.960000000001 |  | D85_LEOPARD_PCIE_RX_DP9 | 442.51 |  | D85_LEOPARD_PCIE_RX_C_DP9 | 116.82 | 1772.07 | 2331.3999999999996 |  | 16216.36 |  | yes; within 19 inch |  |  |  |  |  |  |  |  |  |  |
| P3E_CPU0_PE2_RISER1_RX_DN_9 |  | 10739.76 | yes; within 5 mils | 10739.76 | yes; within 5 mils | PCIE_SLOT1_RXN9 | 3147.28 | yes; within 1 mils | 13887.04 | yes; within 5 mils | D85_LEOPARD_PCIE_RX_DN9 | 442.46 | yes; within 1 mils | D85_LEOPARD_PCIE_RX_C_DN9 | 119.92 | 1768.97 | 2331.35 | yes; within 1 mils | 16218.390000000001 | yes; within 5 mils | yes; within 19 inch |  |  |  |  |  |  |  |  |  |  |
|  | routing bundle delta | 96.049999999999272 | yes; within 500mil | 96.049999999999272 | yes; within 500mil | routing bundle delta | 32.089999999999691 | yes; within 200mil | 127.30999999999949 | yes; within 500mil | routing bundle delta | 34.090000000000032 | yes; within 100mil |  |  | routing bundle delta | 68.519999999999527 | yes; within 100mil | 58.790000000000873 | yes; within 500mil |  |  |  |  |  |  |  |  |  |  |  |
| P3E_CPU0_PE2_RISER1_RX_DP_10 |  | 10801.78 |  | 10801.78 |  | PCIE_SLOT1_RXP10 | 3139.23 |  | 13941.01 |  | D85_LEOPARD_PCIE_RX_DP10 | 449.42 |  | D85_LEOPARD_PCIE_RX_C_DP10 | 141.97 | 1927.31 | 2518.6999999999998 |  | 16459.71 |  | yes; within 19 inch |  |  |  |  |  |  |  |  |  |  |
| P3E_CPU0_PE2_RISER1_RX_DN_10 |  | 10802.39 | yes; within 5 mils | 10802.39 | yes; within 5 mils | PCIE_SLOT1_RXN10 | 3138.37 | yes; within 1 mils | 13940.759999999998 | yes; within 5 mils | D85_LEOPARD_PCIE_RX_DN10 | 448.46 | yes; within 1 mils | D85_LEOPARD_PCIE_RX_C_DN10 | 145.13999999999999 | 1924.66 | 2518.2600000000002 | yes; within 1 mils | 16459.019999999997 | yes; within 5 mils | yes; within 19 inch |  |  |  |  |  |  |  |  |  |  |
| P3E_CPU0_PE2_RISER1_RX_DP_11 |  | 10668.28 |  | 10668.28 |  | PCIE_SLOT1_RXP11 | 3140.77 |  | 13809.050000000001 |  | D85_LEOPARD_PCIE_RX_DP11 | 430.12 |  | D85_LEOPARD_PCIE_RX_C_DP11 | 176.66 | 2003.66 | 2610.44 |  | 16419.490000000002 |  | yes; within 19 inch |  |  |  |  |  |  |  |  |  |  |
| P3E_CPU0_PE2_RISER1_RX_DN_11 |  | 10671.6 | yes; within 5 mils | 10671.6 | yes; within 5 mils | PCIE_SLOT1_RXN11 | 3140.56 | yes; within 1 mils | 13812.16 | yes; within 5 mils | D85_LEOPARD_PCIE_RX_DN11 | 430.12 | yes; within 1 mils | D85_LEOPARD_PCIE_RX_C_DN11 | 179.79 | 1999.84 | 2609.75 | yes; within 1 mils | 16421.91 | yes; within 5 mils | yes; within 19 inch |  |  |  |  |  |  |  |  |  |  |
|  | routing bundle delta | 134.10999999999876 | yes; within 500mil | 134.10999999999876 | yes; within 500mil | routing bundle delta | 2.4000000000000909 | yes; within 200mil | 131.95999999999913 | yes; within 500mil | routing bundle delta | 19.300000000000011 | yes; within 100mil |  |  | routing bundle delta | 92.179999999999836 | yes; within 100mil | 40.219999999997526 | yes; within 500mil |  |  |  |  |  |  |  |  |  |  |  |
| P3E_CPU0_PE2_RISER1_RX_DP_12 |  | 10934.83 |  | 10934.83 |  | PCIE_SLOT1_RXP12 | 3140.8 |  | 14075.630000000001 |  | D85_LEOPARD_PCIE_RX_DP12 | 432.61 |  | D85_LEOPARD_PCIE_RX_C_DP12 | 200.79 | 2209.2600000000002 | 2842.6600000000003 |  | 16918.29 |  | yes; within 19 inch |  |  |  |  |  |  |  |  |  |  |
| P3E_CPU0_PE2_RISER1_RX_DN_12 |  | 10934.62 | yes; within 5 mils | 10934.62 | yes; within 5 mils | PCIE_SLOT1_RXN12 | 3140.06 | yes; within 1 mils | 14074.68 | yes; within 5 mils | D85_LEOPARD_PCIE_RX_DN12 | 432.6 | yes; within 1 mils | D85_LEOPARD_PCIE_RX_C_DN12 | 203.9 | 2206.1799999999998 | 2842.68 | yes; within 1 mils | 16917.36 | yes; within 5 mils | yes; within 19 inch |  |  |  |  |  |  |  |  |  |  |
| P3E_CPU0_PE2_RISER1_RX_DP_13 |  | 11193.76 |  | 11193.76 |  | PCIE_SLOT1_RXP13 | 3142.67 |  | 14336.43 |  | D85_LEOPARD_PCIE_RX_DP13 | 427.76 |  | D85_LEOPARD_PCIE_RX_C_DP13 | 240.83 | 2268.41 | 2937 |  | 17273.43 |  | yes; within 19 inch |  |  |  |  |  |  |  |  |  |  |
| P3E_CPU0_PE2_RISER1_RX_DN_13 |  | 11193.98 | yes; within 5 mils | 11193.98 | yes; within 5 mils | PCIE_SLOT1_RXN13 | 3141.98 | yes; within 1 mils | 14335.96 | yes; within 5 mils | D85_LEOPARD_PCIE_RX_DN13 | 427.75 | yes; within 1 mils | D85_LEOPARD_PCIE_RX_C_DN13 | 240.83 | 2268.2399999999998 | 2936.8199999999997 | yes; within 1 mils | 17272.78 | yes; within 5 mils | yes; within 19 inch |  |  |  |  |  |  |  |  |  |  |
|  | routing bundle delta | 259.35999999999876 | yes; within 500mil | 259.35999999999876 | yes; within 500mil | routing bundle delta | 2.6100000000001273 | yes; within 200mil | 261.75 | yes; within 500mil | routing bundle delta | 4.8600000000000136 | yes; within 100mil |  |  | routing bundle delta | 94.339999999999691 | yes; within 100mil | 356.06999999999971 | yes; within 500mil |  |  |  |  |  |  |  |  |  |  |  |
| P3E_CPU0_PE2_RISER1_RX_DP_14 |  | 10830.55 |  | 10830.55 |  | PCIE_SLOT1_RXP14 | 3141.09 |  | 13971.64 |  | D85_LEOPARD_PCIE_RX_DP14 | 431.2 |  | D85_LEOPARD_PCIE_RX_C_DP14 | 261.58 | 2466.4899999999998 | 3159.2699999999995 |  | 17130.91 |  | yes; within 19 inch |  |  |  |  |  |  |  |  |  |  |
| P3E_CPU0_PE2_RISER1_RX_DN_14 |  | 10827.93 | yes; within 5 mils | 10827.93 | yes; within 5 mils | PCIE_SLOT1_RXN14 | 3140.52 | yes; within 1 mils | 13968.45 | yes; within 5 mils | D85_LEOPARD_PCIE_RX_DN14 | 431.17 | yes; within 1 mils | D85_LEOPARD_PCIE_RX_C_DN14 | 264.61 | 2462.75 | 3158.53 | yes; within 1 mils | 17126.98 | yes; within 5 mils | yes; within 19 inch |  |  |  |  |  |  |  |  |  |  |
| P3E_CPU0_PE2_RISER1_RX_DP_15 |  | 10880.45 |  | 10880.45 |  | PCIE_SLOT1_RXP15 | 3141.42 |  | 14021.87 |  | D85_LEOPARD_PCIE_RX_DP15 | 461.16 |  | D85_LEOPARD_PCIE_RX_C_DP15 | 296.16000000000003 | 2500.2600000000002 | 3257.58 |  | 17279.45 |  | yes; within 19 inch |  |  |  |  |  |  |  |  |  |  |
| P3E_CPU0_PE2_RISER1_RX_DN_15 |  | 10879.79 | yes; within 5 mils | 10879.79 | yes; within 5 mils | PCIE_SLOT1_RXN15 | 3140.62 | yes; within 1 mils | 14020.41 | yes; within 5 mils | D85_LEOPARD_PCIE_RX_DN15 | 461.13 | yes; within 1 mils | D85_LEOPARD_PCIE_RX_C_DN15 | 296.16000000000003 | 2500.79 | 3258.08 | yes; within 1 mils | 17278.489999999998 | yes; within 5 mils | yes; within 19 inch |  |  |  |  |  |  |  |  |  |  |
|  | routing bundle delta | 52.520000000000437 | yes; within 500mil | 52.520000000000437 | yes; within 500mil | routing bundle delta | 0.90000000000009095 | yes; within 200mil | 53.420000000000073 | yes; within 500mil | routing bundle delta | 29.990000000000009 | yes; within 100mil |  |  | routing bundle delta | 99.549999999999727 | yes; within 100mil | 152.47000000000116 | yes; within 500mil |  |  |  |  |  |  |  |  |  |  |  |
|  |  |  | diff pair to pair delta | 525.69999999999891 | yes; within 7000mil | diff pair to pair delta | 837.42000000000007 | yes; within 2000mil | 926.42000000000007 | yes; within 7000mil | diff pair to pair delta | 275.20000000000005 | yes; within 2000mil |  |  | diff pair to pair delta | 1110.3899999999999 | yes; within 2000mil | 1109.3400000000001 | yes; within 9000mil |  |  |  |  |  |  |  |  |  |  |  |
| Re-timer card to PEB of PMC |  |  |  |  |  |  |  |  |  |  |  |  |  |  |  |  |  |  |  |  |  |  |  |  |  |  |  |  |  |  |  |
| Re-timer Card |  |  |  |  |  |  |  |  | MiniSAS HD Cable | CN15 of PEB of PMC8536 |  |  |  |  |  | MiniSAS HD Cable | CN16 of PEB of PMC8536 |  |  |  |  |  |  |  |  |  |  |  |  |  |  |
| Net Name | PKG Lengths | PCB Net Length | Differential Match | Net Name | PCB Net Length | Differential Match | Re-timer Total Length | Differential Match | The Length of Cable | Net Name | PCB Net Length | Differential Match | Total Length | Differential Match |  | The Length of Cable | Net Name | PCB Net Length | Differential Match | Total Length | Differential Match |  |  |  |  |  |  |  |  |  |  |
| D85_LIGHT_DOWNSTREAM_PCIE_C_TX_DP0 | 300.99 | 743.87 |  | D85_LIGHT_DOWNSTREAM_PCIE_TX_DP0 | 1736.66 |  | 2781.5200000000004 |  |  | PCIE_RX_P95 | 3183.8 |  | 5965.3200000000006 |  |  |  | PCIE_RX_P15 | 4115.6099999999997 |  | 6897.13 |  |  |  |  |  |  |  |  |  |  |  |
| D85_LIGHT_DOWNSTREAM_PCIE_C_TX_DN0 | 301.20999999999998 | 743.22 | yes; within 1 mils | D85_LIGHT_DOWNSTREAM_PCIE_TX_DN0 | 1737.49 | yes; within 1 mils | 2781.92 | yes; within 1 mils |  | PCIE_RX_N95 | 3183.8 | yes; within 1 mils | 5965.72 | yes; within 5 mils |  |  | PCIE_RX_N15 | 4115.42 | yes; within 1 mils | 6897.34 | yes; within 5 mils |  |  |  |  |  |  |  |  |  |  |
| D85_LIGHT_DOWNSTREAM_PCIE_C_TX_DP1 | 267.02999999999997 | 682.41 |  | D85_LIGHT_DOWNSTREAM_PCIE_TX_DP1 | 1649.06 |  | 2598.5 |  |  | PCIE_RX_P94 | 3093.67 |  | 5692.17 |  |  |  | PCIE_RX_P14 | 3735.3 |  | 6333.8 |  |  |  |  |  |  |  |  |  |  |  |
| D85_LIGHT_DOWNSTREAM_PCIE_C_TX_DN1 | 270.17 | 680.02 | yes; within 1 mils | D85_LIGHT_DOWNSTREAM_PCIE_TX_DN1 | 1648.32 | yes; within 1 mils | 2598.5100000000002 | yes; within 1 mils |  | PCIE_RX_N94 | 3093.86 | yes; within 1 mils | 5692.3700000000008 | yes; within 5 mils |  |  | PCIE_RX_N14 | 3734.83 | yes; within 1 mils | 6333.34 | yes; within 5 mils |  |  |  |  |  |  |  |  |  |  |
|  |  |  |  |  |  | routing bundle delta | 183.42000000000007 | yes; within 200mil |  | routing bundle delta | 90.130000000000109 | yes; within 400mil | 273.55000000000018 | yes; within 600mil |  |  | routing bundle delta | 380.77999999999975 | yes; within 400mil | 564 | yes; within 600mil |  |  |  |  |  |  |  |  |  |  |
| D85_LIGHT_DOWNSTREAM_PCIE_C_TX_DP2 | 237.31 | 736.06 |  | D85_LIGHT_DOWNSTREAM_PCIE_TX_DP2 | 1565 |  | 2538.37 |  |  | PCIE_RX_P93 | 3146.99 |  | 5685.36 |  |  |  | PCIE_RX_P13 | 3566.7 |  | 6105.07 |  |  |  |  |  |  |  |  |  |  |  |
| D85_LIGHT_DOWNSTREAM_PCIE_C_TX_DN2 | 239.85 | 734.29 | yes; within 1 mils | D85_LIGHT_DOWNSTREAM_PCIE_TX_DN2 | 1564.73 | yes; within 1 mils | 2538.87 | yes; within 1 mils |  | PCIE_RX_N93 | 3146.48 | yes; within 1 mils | 5685.35 | yes; within 5 mils |  |  | PCIE_RX_N13 | 3566.44 | yes; within 1 mils | 6105.3099999999995 | yes; within 5 mils |  |  |  |  |  |  |  |  |  |  |
| D85_LIGHT_DOWNSTREAM_PCIE_C_TX_DP3 | 205.94 | 592.86 |  | D85_LIGHT_DOWNSTREAM_PCIE_TX_DP3 | 1823.4 |  | 2622.2 |  |  | PCIE_RX_P92 | 3510.64 |  | 6132.84 |  |  |  | PCIE_RX_P12 | 3463.57 |  | 6085.77 |  |  |  |  |  |  |  |  |  |  |  |
| D85_LIGHT_DOWNSTREAM_PCIE_C_TX_DN3 | 208.59 | 591.05999999999995 | yes; within 1 mils | D85_LIGHT_DOWNSTREAM_PCIE_TX_DN3 | 1823.12 | yes; within 1 mils | 2622.77 | yes; within 1 mils |  | PCIE_RX_N92 | 3509.91 | yes; within 1 mils | 6132.68 | yes; within 5 mils |  |  | PCIE_RX_N12 | 3463.7 | yes; within 1 mils | 6086.4699999999993 | yes; within 5 mils |  |  |  |  |  |  |  |  |  |  |
|  |  |  |  |  |  | routing bundle delta | 84.400000000000091 | yes; within 200mil |  | routing bundle delta | 364.15999999999985 | yes; within 400mil | 447.48999999999978 | yes; within 600mil |  |  | routing bundle delta | 103.12999999999965 | yes; within 400mil | 19.539999999999054 | yes; within 600mil |  |  |  |  |  |  |  |  |  |  |
| D85_LIGHT_DOWNSTREAM_PCIE_C_TX_DP4 | 173.04 | 742.38 |  | D85_LIGHT_DOWNSTREAM_PCIE_TX_DP4 | 1629.7 |  | 2545.12 |  |  | PCIE_RX_P91 | 3483.87 |  | 6028.99 |  |  |  | PCIE_RX_P11 | 3131.25 |  | 5676.37 |  |  |  |  |  |  |  |  |  |  |  |
| D85_LIGHT_DOWNSTREAM_PCIE_C_TX_DN4 | 176.1 | 738.56 | yes; within 1 mils | D85_LIGHT_DOWNSTREAM_PCIE_TX_DN4 | 1630.37 | yes; within 1 mils | 2545.0299999999997 | yes; within 1 mils |  | PCIE_RX_N91 | 3483.27 | yes; within 1 mils | 6028.2999999999993 | yes; within 5 mils |  |  | PCIE_RX_N11 | 3130.7 | yes; within 1 mils | 5675.73 | yes; within 5 mils |  |  |  |  |  |  |  |  |  |  |
| D85_LIGHT_DOWNSTREAM_PCIE_C_TX_DP5 | 136.4 | 629.55999999999995 |  | D85_LIGHT_DOWNSTREAM_PCIE_TX_DP5 | 1586.01 |  | 2351.9699999999998 |  |  | PCIE_RX_P90 | 3400.82 |  | 5752.79 |  |  |  | PCIE_RX_P10 | 2822.92 |  | 5174.8899999999994 |  |  |  |  |  |  |  |  |  |  |  |
| D85_LIGHT_DOWNSTREAM_PCIE_C_TX_DN5 | 139.57 | 627.02 | yes; within 1 mils | D85_LIGHT_DOWNSTREAM_PCIE_TX_DN5 | 1586.27 | yes; within 1 mils | 2352.8599999999997 | yes; within 1 mils |  | PCIE_RX_N90 | 3400.24 | yes; within 1 mils | 5753.0999999999995 | yes; within 5 mils |  |  | PCIE_RX_N10 | 2822.77 | yes; within 1 mils | 5175.6299999999992 | yes; within 5 mils |  |  |  |  |  |  |  |  |  |  |
|  |  |  |  |  |  | routing bundle delta | 193.15000000000009 | yes; within 200mil |  | routing bundle delta | 83.630000000000109 | yes; within 400mil | 276.19999999999982 | yes; within 600mil |  |  | routing bundle delta | 308.48 | yes; within 400mil | 501.48000000000047 | yes; within 600mil |  |  |  |  |  |  |  |  |  |  |
| D85_LIGHT_DOWNSTREAM_PCIE_C_TX_DP6 | 114.25 | 694.85 |  | D85_LIGHT_DOWNSTREAM_PCIE_TX_DP6 | 1447.4 |  | 2256.5 |  |  | PCIE_RX_P89 | 3440.34 |  | 5696.84 |  |  |  | PCIE_RX_P9 | 2861.04 |  | 5117.54 |  |  |  |  |  |  |  |  |  |  |  |
| D85_LIGHT_DOWNSTREAM_PCIE_C_TX_DN6 | 117.41 | 690.82 | yes; within 1 mils | D85_LIGHT_DOWNSTREAM_PCIE_TX_DN6 | 1447.37 | yes; within 1 mils | 2255.6 | yes; within 1 mils |  | PCIE_RX_N89 | 3439.94 | yes; within 1 mils | 5695.54 | yes; within 5 mils |  |  | PCIE_RX_N9 | 2860.58 | yes; within 1 mils | 5116.18 | yes; within 5 mils |  |  |  |  |  |  |  |  |  |  |
| D85_LIGHT_DOWNSTREAM_PCIE_C_TX_DP7 | 98.27 | 584.19000000000005 |  | D85_LIGHT_DOWNSTREAM_PCIE_TX_DP7 | 1753.92 |  | 2436.38 |  |  | PCIE_RX_P88 | 3832.66 |  | 6269.04 |  |  |  | PCIE_RX_P8 | 2818.69 |  | 5255.07 |  |  |  |  |  |  |  |  |  |  |  |
| D85_LIGHT_DOWNSTREAM_PCIE_C_TX_DN7 | 101.45 | 581.9 | yes; within 1 mils | D85_LIGHT_DOWNSTREAM_PCIE_TX_DN7 | 1753.24 | yes; within 1 mils | 2436.59 | yes; within 1 mils |  | PCIE_RX_N88 | 3832.2 | yes; within 1 mils | 6268.79 | yes; within 5 mils |  |  | PCIE_RX_N8 | 2818.52 | yes; within 1 mils | 5255.1100000000006 | yes; within 5 mils |  |  |  |  |  |  |  |  |  |  |
|  |  |  |  |  |  | routing bundle delta | 180.99000000000024 | yes; within 200mil |  | routing bundle delta | 392.7199999999998 | yes; within 400mil | 573.5 | yes; within 600mil |  |  | routing bundle delta | 42.519999999999982 | yes; within 400mil | 138.93000000000029 | yes; within 600mil |  |  |  |  |  |  |  |  |  |  |
| D85_LIGHT_DOWNSTREAM_PCIE_C_TX_DP8 | 105.84 | 685.98 |  | D85_LIGHT_DOWNSTREAM_PCIE_TX_DP8 | 1602.78 |  | 2394.6 |  |  | PCIE_RX_P87 | 3795.74 |  | 6190.34 |  |  |  | PCIE_RX_P7 | 2830.92 |  | 5225.5200000000004 |  |  |  |  |  |  |  |  |  |  |  |
| D85_LIGHT_DOWNSTREAM_PCIE_C_TX_DN8 | 108.94 | 683.46 | yes; within 1 mils | D85_LIGHT_DOWNSTREAM_PCIE_TX_DN8 | 1602.58 | yes; within 1 mils | 2394.98 | yes; within 1 mils |  | PCIE_RX_N87 | 3796.49 | yes; within 1 mils | 6191.4699999999993 | yes; within 5 mils |  |  | PCIE_RX_N7 | 2831.19 | yes; within 1 mils | 5226.17 | yes; within 5 mils |  |  |  |  |  |  |  |  |  |  |
| D85_LIGHT_DOWNSTREAM_PCIE_C_TX_DP9 | 114.71 | 614.29 |  | D85_LIGHT_DOWNSTREAM_PCIE_TX_DP9 | 1471.35 |  | 2200.35 |  |  | PCIE_RX_P86 | 3550.96 |  | 5751.3099999999995 |  |  |  | PCIE_RX_P6 | 2544.83 |  | 4745.18 |  |  |  |  |  |  |  |  |  |  |  |
| D85_LIGHT_DOWNSTREAM_PCIE_C_TX_DN9 | 117.99 | 611.11 | yes; within 1 mils | D85_LIGHT_DOWNSTREAM_PCIE_TX_DN9 | 1470.36 | yes; within 1 mils | 2199.46 | yes; within 1 mils |  | PCIE_RX_N86 | 3550.27 | yes; within 1 mils | 5749.73 | yes; within 5 mils |  |  | PCIE_RX_N6 | 2544.16 | yes; within 1 mils | 4743.62 | yes; within 5 mils |  |  |  |  |  |  |  |  |  |  |
|  |  |  |  |  |  | routing bundle delta | 195.51999999999998 | yes; within 200mil |  | routing bundle delta | 246.2199999999998 | yes; within 400mil | 441.73999999999978 | yes; within 600mil |  |  | routing bundle delta | 287.0300000000002 | yes; within 400mil | 482.55000000000018 | yes; within 600mil |  |  |  |  |  |  |  |  |  |  |
| D85_LIGHT_DOWNSTREAM_PCIE_C_TX_DP10 | 131.9 | 630.41 |  | D85_LIGHT_DOWNSTREAM_PCIE_TX_DP10 | 1596.61 |  | 2358.92 |  |  | PCIE_RX_P85 | 3892.44 |  | 6251.3600000000006 |  |  |  | PCIE_RX_P5 | 2544.8200000000002 |  | 4903.74 |  |  |  |  |  |  |  |  |  |  |  |
| D85_LIGHT_DOWNSTREAM_PCIE_C_TX_DN10 | 135.19 | 627.49 | yes; within 1 mils | D85_LIGHT_DOWNSTREAM_PCIE_TX_DN10 | 1595.67 | yes; within 1 mils | 2358.3500000000004 | yes; within 1 mils |  | PCIE_RX_N85 | 3892.46 | yes; within 1 mils | 6250.81 | yes; within 5 mils |  |  | PCIE_RX_N5 | 2545.6 | yes; within 1 mils | 4903.9500000000007 | yes; within 5 mils |  |  |  |  |  |  |  |  |  |  |
| D85_LIGHT_DOWNSTREAM_PCIE_C_TX_DP11 | 167.4 | 607.23 |  | D85_LIGHT_DOWNSTREAM_PCIE_TX_DP11 | 1752.68 |  | 2527.31 |  |  | PCIE_RX_P84 | 4263.2 |  | 6790.51 |  |  |  | PCIE_RX_P4 | 2726.94 |  | 5254.25 |  |  |  |  |  |  |  |  |  |  |  |
| D85_LIGHT_DOWNSTREAM_PCIE_C_TX_DN11 | 170.57 | 603.5 | yes; within 1 mils | D85_LIGHT_DOWNSTREAM_PCIE_TX_DN11 | 1752.25 | yes; within 1 mils | 2526.3199999999997 | yes; within 1 mils |  | PCIE_RX_N84 | 4262.38 | yes; within 1 mils | 6788.7 | yes; within 5 mils |  |  | PCIE_RX_N4 | 2726.34 | yes; within 1 mils | 5252.66 | yes; within 5 mils |  |  |  |  |  |  |  |  |  |  |
|  |  |  |  |  |  | routing bundle delta | 168.95999999999958 | yes; within 200mil |  | routing bundle delta | 370.75999999999976 | yes; within 400mil | 539.69999999999982 | yes; within 600mil |  |  | routing bundle delta | 182.11999999999989 | yes; within 400mil | 350.51000000000022 | yes; within 600mil |  |  |  |  |  |  |  |  |  |  |
| D85_LIGHT_DOWNSTREAM_PCIE_C_TX_DP12 | 196.36 | 708.53 |  | D85_LIGHT_DOWNSTREAM_PCIE_TX_DP12 | 1599.8 |  | 2504.69 |  |  | PCIE_RX_P83 | 4460 |  | 6964.6900000000005 |  |  |  | PCIE_RX_P3 | 2244.1 |  | 4748.79 |  |  |  |  |  |  |  |  |  |  |  |
| D85_LIGHT_DOWNSTREAM_PCIE_C_TX_DN12 | 199.39 | 706.26 | yes; within 1 mils | D85_LIGHT_DOWNSTREAM_PCIE_TX_DN12 | 1599.55 | yes; within 1 mils | 2505.1999999999998 | yes; within 1 mils |  | PCIE_RX_N83 | 4460.3599999999997 | yes; within 1 mils | 6965.5599999999995 | yes; within 5 mils |  |  | PCIE_RX_N3 | 2244.66 | yes; within 1 mils | 4749.8599999999997 | yes; within 5 mils |  |  |  |  |  |  |  |  |  |  |
| D85_LIGHT_DOWNSTREAM_PCIE_C_TX_DP13 | 231.9 | 672.54 |  | D85_LIGHT_DOWNSTREAM_PCIE_TX_DP13 | 1463.69 |  | 2368.13 |  |  | PCIE_RX_P82 | 4286.6899999999996 |  | 6654.82 |  |  |  | PCIE_RX_P2 | 2274.42 |  | 4642.55 |  |  |  |  |  |  |  |  |  |  |  |
| D85_LIGHT_DOWNSTREAM_PCIE_C_TX_DN13 | 234.98 | 670.42 | yes; within 1 mils | D85_LIGHT_DOWNSTREAM_PCIE_TX_DN13 | 1463.18 | yes; within 1 mils | 2368.58 | yes; within 1 mils |  | PCIE_RX_N82 | 4287.53 | yes; within 1 mils | 6656.11 | yes; within 5 mils |  |  | PCIE_RX_N2 | 2275.35 | yes; within 1 mils | 4643.93 | yes; within 5 mils |  |  |  |  |  |  |  |  |  |  |
|  |  |  |  |  |  | routing bundle delta | 137.06999999999971 | yes; within 200mil |  | routing bundle delta | 173.67000000000007 | yes; within 400mil | 310.73999999999978 | yes; within 600mil |  |  | routing bundle delta | 31.25 | yes; within 400mil | 107.30999999999949 | yes; within 600mil |  |  |  |  |  |  |  |  |  |  |
| D85_LIGHT_DOWNSTREAM_PCIE_C_TX_DP14 | 256.16000000000003 | 652.34 |  | D85_LIGHT_DOWNSTREAM_PCIE_TX_DP14 | 1640.07 |  | 2548.5699999999997 |  |  | PCIE_RX_P81 | 4601.58 |  | 7150.15 |  |  |  | PCIE_RX_P1 | 2670.32 |  | 5218.8899999999994 |  |  |  |  |  |  |  |  |  |  |  |
| D85_LIGHT_DOWNSTREAM_PCIE_C_TX_DN14 | 259.3 | 649.5 | yes; within 1 mils | D85_LIGHT_DOWNSTREAM_PCIE_TX_DN14 | 1639.46 | yes; within 1 mils | 2548.2600000000002 | yes; within 1 mils |  | PCIE_RX_N81 | 4601.13 | yes; within 1 mils | 7149.39 | yes; within 5 mils |  |  | PCIE_RX_N1 | 2669.7 | yes; within 1 mils | 5217.96 | yes; within 5 mils |  |  |  |  |  |  |  |  |  |  |
| D85_LIGHT_DOWNSTREAM_PCIE_C_TX_DP15 | 290.93 | 669.17 |  | D85_LIGHT_DOWNSTREAM_PCIE_TX_DP15 | 1744.95 |  | 2705.05 |  |  | PCIE_RX_P80 | 4960.47 |  | 7665.52 |  |  |  | PCIE_RX_P0 | 3035.09 |  | 5740.14 |  |  |  |  |  |  |  |  |  |  |  |
| D85_LIGHT_DOWNSTREAM_PCIE_C_TX_DN15 | 290.93 | 669.4 | yes; within 1 mils | D85_LIGHT_DOWNSTREAM_PCIE_TX_DN15 | 1745.46 | yes; within 1 mils | 2705.79 | yes; within 1 mils |  | PCIE_RX_N80 | 4960 | yes; within 1 mils | 7665.79 | yes; within 5 mils |  |  | PCIE_RX_N0 | 3034.17 | yes; within 1 mils | 5739.96 | yes; within 5 mils |  |  |  |  |  |  |  |  |  |  |
|  |  |  |  |  |  | routing bundle delta | 157.52999999999975 | yes; within 200mil |  | routing bundle delta | 359.34000000000015 | yes; within 400mil | 516.39999999999964 | yes; within 600mil |  |  | routing bundle delta | 365.39000000000033 | yes; within 400mil | 522.18000000000029 | yes; within 600mil |  |  |  |  |  |  |  |  |  |  |
|  |  |  |  |  |  | diff pair to pair delta | 582.46 | yes; within 1000mil |  | diff pair to pair delta | 1866.8000000000002 | yes; within 2000mil | 1980.4399999999996 | yes; within 9000mil |  |  | diff pair to pair delta | 887.15000000000009 | yes; within 2000mil | 2254.79 | yes; within 9000mil |  |  |  |  |  |  |  |  |  |  |
| Re-timer Card |  |  |  |  |  |  |  |  | MiniSAS HD Cable | CN15 of PEB of PMC8536 |  |  |  |  |  |  |  |  |  |  | MiniSAS HD Cable | CN16 of PEB of PMC8536 |  |  |  |  |  |  |  |  |  |
| Net Name | PKG Lengths | PCB Net Length | Differential Match | Net Name | PCB Net Length | Differential Match | Re-timer Total Length | Differential Match | The Length of Cable | Net Name | PCB Net Length | Differential Match | Net Name | PCB Net Length | Differential Match | PEB Total Length | Differential Match | Total Length | Differential Match |  | The Length of Cable | Net Name | PCB Net Length | Differential Match | Net Name | PCB Net Length | Differential Match | PEB Total Length | Differential Match | Total Length | Differential Match |
| D85_LIGHT_DOWNSTREAM_PCIE_RX_DP0 | 321.44 | 2672.78 |  |  |  |  | 2994.2200000000003 |  |  | PCIE_TX_P95 | 455.19 |  | PCIE_TX_CAP_P95 | 2222.3000000000002 |  | 2677.4900000000002 |  | 5671.7100000000009 |  |  |  | PCIE_TX_P15 | 579.05999999999995 |  | PCIE_TX_CAP_P15 | 3274.18 |  | 3853.24 |  | 6847.46 |  |
| D85_LIGHT_DOWNSTREAM_PCIE_RX_DN0 | 324.77 | 2668.84 | yes; within 1 mils |  |  |  | 2993.61 | yes; within 1 mils |  | PCIE_TX_N95 | 455.55 | yes; within 1 mils | PCIE_TX_CAP_N95 | 2222.27 | yes; within 1 mils | 2677.82 | yes; within 1 mils | 5671.43 | yes; within 5 mils |  |  | PCIE_TX_N15 | 578.99 | yes; within 1 mils | PCIE_TX_CAP_N15 | 3273.85 | yes; within 1 mils | 3852.84 | yes; within 1 mils | 6846.4500000000007 | yes; within 5 mils |
| D85_LIGHT_DOWNSTREAM_PCIE_RX_DP1 | 302.18 | 2492.8000000000002 |  |  |  |  | 2794.98 |  |  | PCIE_TX_P94 | 445.95 |  | PCIE_TX_CAP_P94 | 2176.23 |  | 2622.18 |  | 5417.16 |  |  |  | PCIE_TX_P14 | 404.78 |  | PCIE_TX_CAP_P14 | 3158.42 |  | 3563.2 |  | 6358.18 |  |
| D85_LIGHT_DOWNSTREAM_PCIE_RX_DN1 | 305.58999999999997 | 2490.27 | yes; within 1 mils |  |  |  | 2795.86 | yes; within 1 mils |  | PCIE_TX_N94 | 445.95 | yes; within 1 mils | PCIE_TX_CAP_N94 | 2176.7399999999998 | yes; within 1 mils | 2622.6899999999996 | yes; within 1 mils | 5418.5499999999993 | yes; within 5 mils |  |  | PCIE_TX_N14 | 404.64 | yes; within 1 mils | PCIE_TX_CAP_N14 | 3159.06 | yes; within 1 mils | 3563.7 | yes; within 1 mils | 6359.5599999999995 | yes; within 5 mils |
|  |  |  |  |  |  | routing bundle delta | 199.24000000000024 | yes; within 200mil |  | routing bundle delta | 9.6000000000000227 |  | routing bundle delta | 46.070000000000164 | routing bundle delta | 55.640000000000327 | yes; within 400mil | 254.55000000000109 | yes; within 600mil |  |  | routing bundle delta | 174.41999999999996 |  | routing bundle delta | 115.75999999999976 | routing bundle delta | 290.03999999999996 | yes; within 400mil | 489.27999999999975 | yes; within 600mil |
| D85_LIGHT_DOWNSTREAM_PCIE_RX_DP2 | 266.51 | 2462.34 |  |  |  |  | 2728.8500000000004 |  |  | PCIE_TX_P93 | 640.89 |  | PCIE_TX_CAP_P93 | 2036.01 |  | 2676.9 |  | 5405.75 |  |  |  | PCIE_TX_P13 | 389.31 |  | PCIE_TX_CAP_P13 | 3050.93 |  | 3440.24 |  | 6169.09 |  |
| D85_LIGHT_DOWNSTREAM_PCIE_RX_DN2 | 269.97000000000003 | 2459.85 | yes; within 1 mils |  |  |  | 2729.8199999999997 | yes; within 1 mils |  | PCIE_TX_N93 | 641.12 | yes; within 1 mils | PCIE_TX_CAP_N93 | 2036.36 | yes; within 1 mils | 2677.48 | yes; within 1 mils | 5407.2999999999993 | yes; within 5 mils |  |  | PCIE_TX_N13 | 389.95 | yes; within 1 mils | PCIE_TX_CAP_N13 | 3050.72 | yes; within 1 mils | 3440.6699999999996 | yes; within 1 mils | 6170.49 | yes; within 5 mils |
| D85_LIGHT_DOWNSTREAM_PCIE_RX_DP3 | 242.29 | 2584.2199999999998 |  |  |  |  | 2826.5099999999998 |  |  | PCIE_TX_P92 | 555.48 |  | PCIE_TX_CAP_P92 | 2056.69 |  | 2612.17 |  | 5438.68 |  |  |  | PCIE_TX_P12 | 669.04 |  | PCIE_TX_CAP_P12 | 2894.91 |  | 3563.95 |  | 6390.4599999999991 |  |
| D85_LIGHT_DOWNSTREAM_PCIE_RX_DN3 | 245.91 | 2581.39 | yes; within 1 mils |  |  |  | 2827.2999999999997 | yes; within 1 mils |  | PCIE_TX_N92 | 555.75 | yes; within 1 mils | PCIE_TX_CAP_N92 | 2056.38 | yes; within 1 mils | 2612.13 | yes; within 1 mils | 5439.43 | yes; within 5 mils |  |  | PCIE_TX_N12 | 669.56 | yes; within 1 mils | PCIE_TX_CAP_N12 | 2894.99 | yes; within 1 mils | 3564.5499999999997 | yes; within 1 mils | 6391.8499999999995 | yes; within 5 mils |
|  |  |  |  |  |  | routing bundle delta | 98.449999999999363 | yes; within 200mil |  | routing bundle delta | 85.639999999999986 |  | routing bundle delta | 20.680000000000064 | routing bundle delta | 65.349999999999909 | yes; within 400mil | 33.680000000000291 | yes; within 600mil |  |  | routing bundle delta | 280.24999999999994 |  | routing bundle delta | 156.01999999999998 | routing bundle delta | 124.30999999999995 | yes; within 400mil | 222.75999999999931 | yes; within 600mil |
| D85_LIGHT_DOWNSTREAM_PCIE_RX_DP4 | 232.17 | 2481.48 |  |  |  |  | 2713.65 |  |  | PCIE_TX_P91 | 1081.56 |  | PCIE_TX_CAP_P91 | 1856.47 |  | 2938.0299999999997 |  | 5651.68 |  |  |  | PCIE_TX_P11 | 543.41999999999996 |  | PCIE_TX_CAP_P11 | 2703.49 |  | 3246.91 |  | 5960.5599999999995 |  |
| D85_LIGHT_DOWNSTREAM_PCIE_RX_DN4 | 235.59 | 2477.1 | yes; within 1 mils |  |  |  | 2712.69 | yes; within 1 mils |  | PCIE_TX_N91 | 1081.75 | yes; within 1 mils | PCIE_TX_CAP_N91 | 1856.09 | yes; within 1 mils | 2937.84 | yes; within 1 mils | 5650.5300000000007 | yes; within 5 mils |  |  | PCIE_TX_N11 | 543.38 | yes; within 1 mils | PCIE_TX_CAP_N11 | 2703.37 | yes; within 1 mils | 3246.75 | yes; within 1 mils | 5959.4400000000005 | yes; within 5 mils |
| D85_LIGHT_DOWNSTREAM_PCIE_RX_DP5 | 214.43 | 2328.62 |  |  |  |  | 2543.0499999999997 |  |  | PCIE_TX_P90 | 400.32 |  | PCIE_TX_CAP_P90 | 2763.98 |  | 3164.3 |  | 5707.35 |  |  |  | PCIE_TX_P10 | 374.94 |  | PCIE_TX_CAP_P10 | 2564.15 |  | 2939.09 |  | 5482.1399999999994 |  |
| D85_LIGHT_DOWNSTREAM_PCIE_RX_DN5 | 217.85 | 2324.7199999999998 | yes; within 1 mils |  |  |  | 2542.5699999999997 | yes; within 1 mils |  | PCIE_TX_N90 | 400.47 | yes; within 1 mils | PCIE_TX_CAP_N90 | 2763.99 | yes; within 1 mils | 3164.46 | yes; within 1 mils | 5707.03 | yes; within 5 mils |  |  | PCIE_TX_N10 | 374.64 | yes; within 1 mils | PCIE_TX_CAP_N10 | 2564.64 | yes; within 1 mils | 2939.2799999999997 | yes; within 1 mils | 5481.8499999999995 | yes; within 5 mils |
|  |  |  |  |  |  | routing bundle delta | 171.08000000000038 | yes; within 200mil |  | routing bundle delta | 681.43000000000006 |  | routing bundle delta | 907.89999999999986 | routing bundle delta | 226.61999999999989 | yes; within 400mil | 56.819999999999709 | yes; within 600mil |  |  | routing bundle delta | 168.77999999999997 |  | routing bundle delta | 139.33999999999969 | routing bundle delta | 307.81999999999971 | yes; within 400mil | 478.71000000000004 | yes; within 600mil |
| D85_LIGHT_DOWNSTREAM_PCIE_RX_DP6 | 206.42 | 2382.35 |  |  |  |  | 2588.77 |  |  | PCIE_TX_P89 | 378.18 |  | PCIE_TX_CAP_P89 | 2792.88 |  | 3171.06 |  | 5759.83 |  |  |  | PCIE_TX_P9 | 374.13 |  | PCIE_TX_CAP_P9 | 2498.1 |  | 2872.23 |  | 5461 |  |
| D85_LIGHT_DOWNSTREAM_PCIE_RX_DN6 | 209.83 | 2378.04 | yes; within 1 mils |  |  |  | 2587.87 | yes; within 1 mils |  | PCIE_TX_N89 | 378.06 | yes; within 1 mils | PCIE_TX_CAP_N89 | 2792.6 | yes; within 1 mils | 3170.66 | yes; within 1 mils | 5758.53 | yes; within 5 mils |  |  | PCIE_TX_N9 | 375.04 | yes; within 1 mils | PCIE_TX_CAP_N9 | 2497.69 | yes; within 1 mils | 2872.73 | yes; within 1 mils | 5460.6 | yes; within 5 mils |
| D85_LIGHT_DOWNSTREAM_PCIE_RX_DP7 | 196.11 | 2535.36 |  |  |  |  | 2731.4700000000003 |  |  | PCIE_TX_P88 | 633.04 |  | PCIE_TX_CAP_P88 | 2747.08 |  | 3380.12 |  | 6111.59 |  |  |  | PCIE_TX_P8 | 648.27 |  | PCIE_TX_CAP_P8 | 2337.4899999999998 |  | 2985.7599999999998 |  | 5717.23 |  |
| D85_LIGHT_DOWNSTREAM_PCIE_RX_DN7 | 199.53 | 2531.4499999999998 | yes; within 1 mils |  |  |  | 2730.98 | yes; within 1 mils |  | PCIE_TX_N88 | 632.55999999999995 | yes; within 1 mils | PCIE_TX_CAP_N88 | 2747.84 | yes; within 1 mils | 3380.4 | yes; within 1 mils | 6111.38 | yes; within 5 mils |  |  | PCIE_TX_N8 | 648.04999999999995 | yes; within 1 mils | PCIE_TX_CAP_N8 | 2337.34 | yes; within 1 mils | 2985.3900000000003 | yes; within 1 mils | 5716.3700000000008 | yes; within 5 mils |
|  |  |  |  |  |  | routing bundle delta | 143.60000000000036 | yes; within 200mil |  | routing bundle delta | 254.97999999999996 |  | routing bundle delta | 45.800000000000182 | routing bundle delta | 209.74000000000024 | yes; within 400mil | 353.0600000000004 | yes; within 600mil |  |  | routing bundle delta | 274.14 |  | routing bundle delta | 160.75999999999976 | routing bundle delta | 113.52999999999975 | yes; within 400mil | 256.6299999999992 | yes; within 600mil |
| D85_LIGHT_DOWNSTREAM_PCIE_RX_DP8 | 193.61 | 2422.62 |  |  |  |  | 2616.23 |  |  | PCIE_TX_P87 | 578.9 |  | PCIE_TX_CAP_P87 | 3041.65 |  | 3620.55 |  | 6236.7800000000007 |  |  |  | PCIE_TX_P7 | 542.92999999999995 |  | PCIE_TX_CAP_P7 | 2215.67 |  | 2758.6 |  | 5374.83 |  |
| D85_LIGHT_DOWNSTREAM_PCIE_RX_DN8 | 196.94 | 2420.06 | yes; within 1 mils |  |  |  | 2617 | yes; within 1 mils |  | PCIE_TX_N87 | 578.54999999999995 | yes; within 1 mils | PCIE_TX_CAP_N87 | 3041.83 | yes; within 1 mils | 3620.38 | yes; within 1 mils | 6237.38 | yes; within 5 mils |  |  | PCIE_TX_N7 | 542.96 | yes; within 1 mils | PCIE_TX_CAP_N7 | 2215.8000000000002 | yes; within 1 mils | 2758.76 | yes; within 1 mils | 5375.76 | yes; within 5 mils |
| D85_LIGHT_DOWNSTREAM_PCIE_RX_DP9 | 208.23 | 2280.33 |  |  |  |  | 2488.56 |  |  | PCIE_TX_P86 | 379.5 |  | PCIE_TX_CAP_P86 | 3246.61 |  | 3626.11 |  | 6114.67 |  |  |  | PCIE_TX_P6 | 374.79 |  | PCIE_TX_CAP_P6 | 2235.89 |  | 2610.6799999999998 |  | 5099.24 |  |
| D85_LIGHT_DOWNSTREAM_PCIE_RX_DN9 | 211.72 | 2277.4499999999998 | yes; within 1 mils |  |  |  | 2489.1699999999996 | yes; within 1 mils |  | PCIE_TX_N86 | 379.81 | yes; within 1 mils | PCIE_TX_CAP_N86 | 3247.17 | yes; within 1 mils | 3626.98 | yes; within 1 mils | 6116.15 | yes; within 5 mils |  |  | PCIE_TX_N6 | 374.9 | yes; within 1 mils | PCIE_TX_CAP_N6 | 2235.6999999999998 | yes; within 1 mils | 2610.6 | yes; within 1 mils | 5099.7699999999995 | yes; within 5 mils |
|  |  |  |  |  |  | routing bundle delta | 128.44000000000005 | yes; within 200mil |  | routing bundle delta | 199.39999999999998 |  | routing bundle delta | 205.51999999999998 | routing bundle delta | 6.5999999999999091 | yes; within 400mil | 122.71000000000004 | yes; within 600mil |  |  | routing bundle delta | 168.17000000000002 |  | routing bundle delta | 20.2199999999998 | routing bundle delta | 148.16000000000031 | yes; within 400mil | 276.52000000000044 | yes; within 600mil |
| D85_LIGHT_DOWNSTREAM_PCIE_RX_DP10 | 219.18 | 2332.41 |  |  |  |  | 2551.5899999999997 |  |  | PCIE_TX_P85 | 386.29 |  | PCIE_TX_CAP_P85 | 3316.87 |  | 3703.16 |  | 6254.75 |  |  |  | PCIE_TX_P5 | 375.94 |  | PCIE_TX_CAP_P5 | 2301.77 |  | 2677.71 |  | 5229.2999999999993 |  |
| D85_LIGHT_DOWNSTREAM_PCIE_RX_DN10 | 222.6 | 2328.83 | yes; within 1 mils |  |  |  | 2551.4299999999998 | yes; within 1 mils |  | PCIE_TX_N85 | 386.08 | yes; within 1 mils | PCIE_TX_CAP_N85 | 3316.55 | yes; within 1 mils | 3702.63 | yes; within 1 mils | 6254.0599999999995 | yes; within 5 mils |  |  | PCIE_TX_N5 | 375.87 | yes; within 1 mils | PCIE_TX_CAP_N5 | 2301.4299999999998 | yes; within 1 mils | 2677.2999999999997 | yes; within 1 mils | 5228.7299999999996 | yes; within 5 mils |
| D85_LIGHT_DOWNSTREAM_PCIE_RX_DP11 | 237.59 | 2513.08 |  |  |  |  | 2750.67 |  |  | PCIE_TX_P84 | 603.11 |  | PCIE_TX_CAP_P84 | 3241.19 |  | 3844.3 |  | 6594.97 |  |  |  | PCIE_TX_P4 | 662.81 |  | PCIE_TX_CAP_P4 | 2095.09 |  | 2757.9 |  | 5508.57 |  |
| D85_LIGHT_DOWNSTREAM_PCIE_RX_DN11 | 241.33 | 2509.79 | yes; within 1 mils |  |  |  | 2751.12 | yes; within 1 mils |  | PCIE_TX_N84 | 602.87 | yes; within 1 mils | PCIE_TX_CAP_N84 | 3241.77 | yes; within 1 mils | 3844.64 | yes; within 1 mils | 6595.76 | yes; within 5 mils |  |  | PCIE_TX_N4 | 662.13 | yes; within 1 mils | PCIE_TX_CAP_N4 | 2095.91 | yes; within 1 mils | 2758.04 | yes; within 1 mils | 5509.16 | yes; within 5 mils |
|  |  |  |  |  |  | routing bundle delta | 199.69000000000005 | yes; within 200mil |  | routing bundle delta | 217.03000000000003 |  | routing bundle delta | 75.679999999999836 | routing bundle delta | 142.00999999999976 | yes; within 400mil | 341.70000000000073 | yes; within 600mil |  |  | routing bundle delta | 286.93999999999994 |  | routing bundle delta | 206.67999999999984 | routing bundle delta | 80.740000000000236 | yes; within 400mil | 280.43000000000029 | yes; within 600mil |
| D85_LIGHT_DOWNSTREAM_PCIE_RX_DP12 | 256.93 | 2442.1999999999998 |  |  |  |  | 2699.1299999999997 |  |  | PCIE_TX_P83 | 629.87 |  | PCIE_TX_CAP_P83 | 3607.77 |  | 4237.6400000000003 |  | 6936.77 |  |  |  | PCIE_TX_P3 | 592.85 |  | PCIE_TX_CAP_P3 | 2039.84 |  | 2632.69 |  | 5331.82 |  |
| D85_LIGHT_DOWNSTREAM_PCIE_RX_DN12 | 260.43 | 2438.35 | yes; within 1 mils |  |  |  | 2698.7799999999997 | yes; within 1 mils |  | PCIE_TX_N83 | 630.08000000000004 | yes; within 1 mils | PCIE_TX_CAP_N83 | 3607.97 | yes; within 1 mils | 4238.05 | yes; within 1 mils | 6936.83 | yes; within 5 mils |  |  | PCIE_TX_N3 | 592.85 | yes; within 1 mils | PCIE_TX_CAP_N3 | 2040.12 | yes; within 1 mils | 2632.97 | yes; within 1 mils | 5331.75 | yes; within 5 mils |
| D85_LIGHT_DOWNSTREAM_PCIE_RX_DP13 | 280.89999999999998 | 2319.9699999999998 |  |  |  |  | 2600.87 |  |  | PCIE_TX_P82 | 444.51 |  | PCIE_TX_CAP_P82 | 3834.85 |  | 4279.3599999999997 |  | 6880.23 |  |  |  | PCIE_TX_P2 | 477.06 |  | PCIE_TX_CAP_P2 | 1859.21 |  | 2336.27 |  | 4937.1399999999994 |  |
| D85_LIGHT_DOWNSTREAM_PCIE_RX_DN13 | 284.22000000000003 | 2317.2199999999998 | yes; within 1 mils |  |  |  | 2601.4399999999996 | yes; within 1 mils |  | PCIE_TX_N82 | 445.28 | yes; within 1 mils | PCIE_TX_CAP_N82 | 3834.26 | yes; within 1 mils | 4279.54 | yes; within 1 mils | 6880.98 | yes; within 5 mils |  |  | PCIE_TX_N2 | 477.87 | yes; within 1 mils | PCIE_TX_CAP_N2 | 1858.62 | yes; within 1 mils | 2336.4899999999998 | yes; within 1 mils | 4937.9299999999994 | yes; within 5 mils |
|  |  |  |  |  |  | routing bundle delta | 98.259999999999764 | yes; within 200mil |  | routing bundle delta | 185.57000000000005 |  | routing bundle delta | 227.07999999999993 | routing bundle delta | 41.899999999999636 | yes; within 400mil | 56.600000000000364 | yes; within 600mil |  |  | routing bundle delta | 115.79000000000002 |  | routing bundle delta | 181.5 | routing bundle delta | 296.69999999999982 | yes; within 400mil | 394.68000000000029 | yes; within 600mil |
| D85_LIGHT_DOWNSTREAM_PCIE_RX_DP14 | 299.11 | 2526.88 |  |  |  |  | 2825.9900000000002 |  |  | PCIE_TX_P81 | 444.61 |  | PCIE_TX_CAP_P81 | 3898.16 |  | 4342.7699999999995 |  | 7168.76 |  |  |  | PCIE_TX_P1 | 1043.31 |  | PCIE_TX_CAP_P1 | 1390.88 |  | 2434.19 |  | 5260.18 |  |
| D85_LIGHT_DOWNSTREAM_PCIE_RX_DN14 | 302.52999999999997 | 2522.75 | yes; within 1 mils |  |  |  | 2825.2799999999997 | yes; within 1 mils |  | PCIE_TX_N81 | 444.19 | yes; within 1 mils | PCIE_TX_CAP_N81 | 3898.46 | yes; within 1 mils | 4342.6499999999996 | yes; within 1 mils | 7167.9299999999994 | yes; within 5 mils |  |  | PCIE_TX_N1 | 1042.57 | yes; within 1 mils | PCIE_TX_CAP_N1 | 1390.92 | yes; within 1 mils | 2433.4899999999998 | yes; within 1 mils | 5258.7699999999995 | yes; within 5 mils |
| D85_SI_RX_DP15 | 329.62 | 498.24 |  | D85_LIGHT_DOWNSTREAM_PCIE_RX_DP15 | 2009.47 |  | 2837.33 |  |  | PCIE_TX_P80 | 661.63 |  | PCIE_TX_CAP_P80 | 3821.14 |  | 4482.7699999999995 |  | 7320.0999999999995 |  |  |  | PCIE_TX_P0 | 718.83 |  | PCIE_TX_CAP_P0 | 1403.24 |  | 2122.0700000000002 |  | 4959.3999999999996 |  |
| D85_SI_RX_DN15 | 332.95 | 494.06 | yes; within 1 mils | D85_LIGHT_DOWNSTREAM_PCIE_RX_DN15 | 2009.81 | yes; within 1 mils | 2836.8199999999997 | yes; within 1 mils |  | PCIE_TX_N80 | 661.48 | yes; within 1 mils | PCIE_TX_CAP_N80 | 3821.01 | yes; within 1 mils | 4482.49 | yes; within 1 mils | 7319.3099999999995 | yes; within 5 mils |  |  | PCIE_TX_N0 | 718.19 | yes; within 1 mils | PCIE_TX_CAP_N0 | 1403.74 | yes; within 1 mils | 2121.9300000000003 | yes; within 1 mils | 4958.75 | yes; within 5 mils |
|  |  |  |  |  |  | routing bundle delta | 12.050000000000182 | yes; within 200mil |  | routing bundle delta | 217.44 |  | routing bundle delta | 77.449999999999818 | routing bundle delta | 140.11999999999989 | yes; within 400mil | 152.17000000000007 | yes; within 600mil |  |  | routing bundle delta | 325.11999999999989 |  | routing bundle delta | 12.8599999999999 | routing bundle delta | 312.25999999999976 | yes; within 400mil | 301.43000000000029 | yes; within 600mil |
|  |  |  |  |  |  | diff pair to pair delta | 505.66000000000031 | yes; within 1000mil |  | diff pair to pair delta | 703.69 |  | diff pair to pair delta | 2042.3700000000001 | diff pair to pair delta | 1870.6399999999994 | yes; within 2000mil | 1914.3499999999995 | yes; within 9000mil |  |  | diff pair to pair delta | 669.18 |  | diff pair to pair delta | 1883.2999999999997 | diff pair to pair delta | 1731.3099999999995 | yes; within 2000mil | 1910.3200000000006 | yes; within 9000mil |
| PM8536 to SSD0 |  |  |  |  |  |  |  |  |  |  |  |  |  |  |  |  | PCISLT68-14-GP-U | SKT-SAS28-P15-PCIE25-2-GP |  |  |  |  |  |  |  |  |  |  |  |  |  |
| PM8536 to GF of PEB |  |  |  |  |  |  |  |  | Card Edge Connector | Connector of PDPB to U.2 Connector (J0) |  |  |  |  | SFF-8639 Conn | SFF-8639 Conn | M.2 Conn |  |  |  |  |  |  |  |  |  |  |  |  |  |  |
| Net Name | PKG Lengths | PCB Net Length | Differential Match | Net Name | PCB Net Length | Differential Match | PEB Total Length | Differential Match | The Length of Connector | Net Name | PCB Net Length | Differential Match | Total Length | Differential Match | Pin of Connector | Pin of Connector | Net Name | PCB Net Length | Differential Match | Total Length | Differential Match |  |  |  |  |  |  |  |  |  |  |
| PCIE_TX_CAP_N68 |  | 8813.09 |  | PCIE_TX_N68 | 505.21 |  | 9318.2999999999993 |  |  | PE_TX1_DR0_N | 10237.549999999999 |  | 19555.849999999999 |  | E10 | E10 | D85_PCIE_A_TX0_P | 1053.4100000000001 |  | 20609.259999999998 |  |  |  |  |  |  |  |  |  |  |  |
| PCIE_TX_CAP_P68 |  | 8813.48 | yes; within 1 mils | PCIE_TX_P68 | 505.2 | yes; within 1 mils | 9318.68 | yes; within 1 mils |  | PE_TX1_DR0_P | 10237.469999999999 | yes; within 1 mils | 19556.150000000001 | yes; within 5 mils | E11 | E11 | D85_PCIE_A_TX0_N | 1053.3499999999999 | yes; within 1 mils | 20609.5 | yes; within 5 mils |  |  |  |  |  |  |  |  |  |  |
| PCIE_TX_CAP_N69 |  | 9166.42 |  | PCIE_TX_N69 | 505.21 |  | 9671.6299999999992 |  |  | PE_TX2_DR0_N | 10090.61 |  | 19762.239999999998 |  | S17 | S17 | D85_PCIE_A_TX1_P | 1230.57 |  | 20992.809999999998 |  |  |  |  |  |  |  |  |  |  |  |
| PCIE_TX_CAP_P69 |  | 9167.2999999999993 | yes; within 1 mils | PCIE_TX_P69 | 505.2 | yes; within 1 mils | 9672.5 | yes; within 1 mils |  | PE_TX2_DR0_P | 10090.709999999999 | yes; within 1 mils | 19763.21 | yes; within 5 mils | S18 | S18 | D85_PCIE_A_TX1_N | 1230.52 | yes; within 1 mils | 20993.73 | yes; within 5 mils |  |  |  |  |  |  |  |  |  |  |
|  |  |  |  |  |  | routing bundle delta | 354.20000000000073 |  |  | routing bundle delta | 146.93999999999869 | routing bundle delta | 207.36000000000058 | yes; within 600mil |  |  | routing bundle delta | 177.22000000000003 | routing bundle delta | 384.47000000000116 |  |  |  |  |  |  |  |  |  |  |  |
| PCIE_TX_CAP_N70 |  | 9354.43 |  | PCIE_TX_N70 | 505.21 |  | 9859.64 |  |  | PE_TX3_DR0_N | 10190.1 |  | 20049.739999999998 |  | S23 | S23 | D85_PCIE_B_TX0_P | 505.9 |  | 20555.64 |  |  |  |  |  |  |  |  |  |  |  |
| PCIE_TX_CAP_P70 |  | 9354.66 | yes; within 1 mils | PCIE_TX_P70 | 505.21 | yes; within 1 mils | 9859.869999999999 | yes; within 1 mils |  | PE_TX3_DR0_P | 10190.34 | yes; within 1 mils | 20050.21 | yes; within 5 mils | S24 | S24 | D85_PCIE_B_TX0_N | 505.9 | yes; within 1 mils | 20556.11 | yes; within 5 mils |  |  |  |  |  |  |  |  |  |  |
| PCIE_TX_CAP_N71 |  | 9466.91 |  | PCIE_TX_N71 | 505.21 |  | 9972.119999999999 |  |  | PE_TX4_DR0_N | 10373.02 |  | 20345.14 |  | E17 | E17 | D85_PCIE_B_TX1_P | 536.89 |  | 20882.03 |  |  |  |  |  |  |  |  |  |  |  |
| PCIE_TX_CAP_P71 |  | 9467 | yes; within 1 mils | PCIE_TX_P71 | 505.2 | yes; within 1 mils | 9972.2000000000007 | yes; within 1 mils |  | PE_TX4_DR0_P | 10372.61 | yes; within 1 mils | 20344.810000000001 | yes; within 5 mils | E18 | E18 | D85_PCIE_B_TX1_N | 536.82000000000005 | yes; within 1 mils | 20881.63 | yes; within 5 mils |  |  |  |  |  |  |  |  |  |  |
|  |  |  |  |  |  | routing bundle delta | 112.56000000000131 | yes; within 200mil |  | routing bundle delta | 182.92000000000007 | routing bundle delta | 295.40000000000146 | yes; within 600mil |  |  | routing bundle delta | 30.990000000000009 | routing bundle delta | 326.38999999999942 |  |  |  |  |  |  |  |  |  |  |  |
|  |  |  |  |  |  | diff pair to pair delta | 653.90000000000146 | yes; within 2000mil |  | diff pair to pair delta | 282.40999999999985 | yes; within 2000mil | 789.29000000000087 | yes; within 2000mil |  |  | diff pair to pair delta | 724.67 | yes; within 2000mil | 438.09000000000015 | yes; within 2000mil |  |  |  |  |  |  |  |  |  |  |
| PM8536 to GF of PEB |  |  |  | Card Edge Connector | Connector of PDPB to U.2 Connector (J0) |  |  |  |  | SFF-8639 Conn | SFF-8639 Conn | M.2 Conn |  |  |  |  |  |  |  |  |  |  |  |  |  |  |  |  |  |  |  |
| Net Name | PKG Lengths | PCB Net Length | Differential Match | The Length of Connector | Net Name | PCB Net Length | Differential Match | Total Length | Differential Match | Pin of Connector | Pin of Connector | Net Name | PCB Net Length | Differential Match | Total Length | Differential Match |  |  |  |  |  |  |  |  |  |  |  |  |  |  |  |
| PCIE_RX_N68 |  | 9621.0499999999993 |  |  | PE_RX1_DR0_N | 10182.700000000001 |  | 19803.75 |  | E13 | E13 | D85_PCIE_A_RX0_N | 1244.06 |  | 21047.81 |  |  |  |  |  |  |  |  |  |  |  |  |  |  |  |  |
| PCIE_RX_P68 |  | 9621.49 | yes; within 1 mils |  | PE_RX1_DR0_P | 10182.27 | yes; within 1 mils | 19803.760000000002 | yes; within 5 mils | E14 | E14 | D85_PCIE_A_RX0_P | 1244.6500000000001 | yes; within 1 mils | 21048.410000000003 | yes; within 5 mils |  |  |  |  |  |  |  |  |  |  |  |  |  |  |  |
| PCIE_RX_N69 |  | 9781.39 |  |  | PE_RX2_DR0_N | 10157.67 |  | 19939.059999999998 |  | S20 | S20 | D85_PCIE_A_RX1_N | 1537.67 |  | 21476.729999999996 |  |  |  |  |  |  |  |  |  |  |  |  |  |  |  |  |
| PCIE_RX_P69 |  | 9780.9599999999991 | yes; within 1 mils |  | PE_RX2_DR0_P | 10157.14 | yes; within 1 mils | 19938.099999999999 | yes; within 5 mils | S21 | S21 | D85_PCIE_A_RX1_P | 1538.32 | yes; within 1 mils | 21476.42 | yes; within 5 mils |  |  |  |  |  |  |  |  |  |  |  |  |  |  |  |
|  | routing bundle delta | 160.34000000000015 |  |  | routing bundle delta | 25.56000000000131 | routing bundle delta | 135.30999999999767 | yes; within 600mil |  |  | routing bundle delta | 294.26 | routing bundle delta | 428.91999999999462 |  |  |  |  |  |  |  |  |  |  |  |  |  |  |  |  |
| PCIE_RX_N70 |  | 10031.85 |  |  | PE_RX3_DR0_N | 10292.31 |  | 20324.16 |  | S26 | S26 | D85_PCIE_B_RX0_N | 946.63 |  | 21270.79 |  |  |  |  |  |  |  |  |  |  |  |  |  |  |  |  |
| PCIE_RX_P70 |  | 10032.16 | yes; within 1 mils |  | PE_RX3_DR0_P | 10292.31 | yes; within 1 mils | 20324.47 | yes; within 5 mils | S27 | S27 | D85_PCIE_B_RX0_P | 947.24 | yes; within 1 mils | 21271.710000000003 | yes; within 5 mils |  |  |  |  |  |  |  |  |  |  |  |  |  |  |  |
| PCIE_RX_N71 |  | 10150.99 |  |  | PE_RX4_DR0_N | 10467.57 |  | 20618.559999999998 |  | E20 | E20 | D85_PCIE_B_RX1_N | 955.34 |  | 21573.899999999998 |  |  |  |  |  |  |  |  |  |  |  |  |  |  |  |  |
| PCIE_RX_P71 |  | 10151.18 | yes; within 1 mils |  | PE_RX4_DR0_P | 10467.49 | yes; within 1 mils | 20618.669999999998 | yes; within 5 mils | E21 | E21 | D85_PCIE_B_RX1_P | 955.96 | yes; within 1 mils | 21574.629999999997 | yes; within 5 mils |  |  |  |  |  |  |  |  |  |  |  |  |  |  |  |
|  | routing bundle delta | 119.32999999999993 |  |  | routing bundle delta | 175.26000000000022 | routing bundle delta | 294.5099999999984 | yes; within 600mil |  |  | routing bundle delta | 9.3300000000000409 | routing bundle delta | 303.83999999999651 |  |  |  |  |  |  |  |  |  |  |  |  |  |  |  |  |
|  | diff pair to pair delta | 530.13000000000102 | yes; within 2000mil |  | diff pair to pair delta | 310.43000000000029 | yes; within 2000mil | 814.91999999999825 | yes; within 2000mil |  |  | diff pair to pair delta | 591.68999999999994 | yes; within 2000mil | 526.81999999999607 | yes; within 2000mil |  |  |  |  |  |  |  |  |  |  |  |  |  |  |  |
| PM8536 to SSD5 |  |  |  |  |  |  |  |  |  |  |  |  |  |  | PCISLT68-14-GP-U | SKT-SAS28-P15-PCIE25-2-GP |  |  |  |  |  |  |  |  |  |  |  |  |  |  |  |
| PM8536 to GF of PEB |  |  |  |  |  |  |  |  | Card Edge Connector | Connector of PDPB to U.2 Connector (J5) |  |  |  |  | SFF-8639 Conn | SFF-8639 Conn | M.2 Conn |  |  |  |  |  |  |  |  |  |  |  |  |  |  |
| Net Name | PKG Lengths | PCB Net Length | Differential Match | Net Name | PCB Net Length | Differential Match | PEB Total Length | Differential Match | The Length of Connector | Net Name | PCB Net Length | Differential Match | Total Length | Differential Match | Pin of Connector | Pin of Connector | Net Name | PCB Net Length | Differential Match | Total Length | Differential Match |  |  |  |  |  |  |  |  |  |  |
| PCIE_TX_CAP_N72 |  | 9734.81 |  | PCIE_TX_N72 | 505.21 |  | 10240.019999999999 |  |  | PE_TX1_DR5_P | 2348.75 |  | 12588.769999999999 |  | E10 | E10 | D85_PCIE_A_TX0_P | 1053.4100000000001 |  | 13642.179999999998 |  |  |  |  |  |  |  |  |  |  |  |
| PCIE_TX_CAP_P72 |  | 9734.42 | yes; within 1 mils | PCIE_TX_P72 | 505.21 | yes; within 1 mils | 10239.629999999999 | yes; within 1 mils |  | PE_TX1_DR5_N | 2348.2800000000002 | yes; within 1 mils | 12587.91 | yes; within 5 mils | E11 | E11 | D85_PCIE_A_TX0_N | 1053.3499999999999 | yes; within 1 mils | 13641.26 | yes; within 5 mils |  |  |  |  |  |  |  |  |  |  |
| PCIE_TX_CAP_N73 |  | 9848.6299999999992 |  | PCIE_TX_N73 | 505.21 |  | 10353.839999999998 |  |  | PE_TX2_DR5_P | 2609.71 |  | 12963.55 |  | S17 | S17 | D85_PCIE_A_TX1_P | 1230.57 |  | 14194.119999999999 |  |  |  |  |  |  |  |  |  |  |  |
| PCIE_TX_CAP_P73 |  | 9848 | yes; within 1 mils | PCIE_TX_P73 | 505.21 | yes; within 1 mils | 10353.209999999999 | yes; within 1 mils |  | PE_TX2_DR5_N | 2609 | yes; within 1 mils | 12962.21 | yes; within 5 mils | S18 | S18 | D85_PCIE_A_TX1_N | 1230.52 | yes; within 1 mils | 14192.73 | yes; within 5 mils |  |  |  |  |  |  |  |  |  |  |
|  |  |  |  |  |  | routing bundle delta | 114.20999999999913 |  |  | routing bundle delta | 261.42999999999984 | routing bundle delta | 375.63999999999942 | yes; within 600mil |  |  | routing bundle delta | 177.22000000000003 | routing bundle delta | 552.85999999999876 |  |  |  |  |  |  |  |  |  |  |  |
| PCIE_TX_CAP_N74 |  | 10005.99 |  | PCIE_TX_N74 | 505.21 |  | 10511.199999999999 |  |  | PE_TX3_DR5_P | 2580.5700000000002 |  | 13091.769999999999 |  | S23 | S23 | D85_PCIE_B_TX0_P | 505.9 |  | 13597.669999999998 |  |  |  |  |  |  |  |  |  |  |  |
| PCIE_TX_CAP_P74 |  | 10005.36 | yes; within 1 mils | PCIE_TX_P74 | 505.2 | yes; within 1 mils | 10510.560000000001 | yes; within 1 mils |  | PE_TX3_DR5_N | 2579.8000000000002 | yes; within 1 mils | 13090.36 | yes; within 5 mils | S24 | S24 | D85_PCIE_B_TX0_N | 505.9 | yes; within 1 mils | 13596.26 | yes; within 5 mils |  |  |  |  |  |  |  |  |  |  |
| PCIE_TX_CAP_N75 |  | 10265.32 |  | PCIE_TX_N75 | 505.21 |  | 10770.529999999999 |  |  | PE_TX4_DR5_P | 2601.0100000000002 |  | 13371.539999999999 |  | E17 | E17 | D85_PCIE_B_TX1_P | 536.89 |  | 13908.429999999998 |  |  |  |  |  |  |  |  |  |  |  |
| PCIE_TX_CAP_P75 |  | 10265.1 | yes; within 1 mils | PCIE_TX_P75 | 505.21 | yes; within 1 mils | 10770.31 | yes; within 1 mils |  | PE_TX4_DR5_N | 2600.2399999999998 | yes; within 1 mils | 13370.55 | yes; within 5 mils | E18 | E18 | D85_PCIE_B_TX1_N | 536.82000000000005 | yes; within 1 mils | 13907.369999999999 | yes; within 5 mils |  |  |  |  |  |  |  |  |  |  |
|  |  |  |  |  |  | routing bundle delta | 259.96999999999753 |  |  | routing bundle delta | 21.210000000000036 | routing bundle delta | 281.17999999999847 | yes; within 600mil |  |  | routing bundle delta | 30.990000000000009 | routing bundle delta | 312.16999999999825 |  |  |  |  |  |  |  |  |  |  |  |
|  |  |  |  |  |  | diff pair to pair delta | 530.89999999999964 | yes; within 2000mil |  | diff pair to pair delta | 261.42999999999984 | yes; within 2000mil | 783.6299999999992 | yes; within 2000mil |  |  | diff pair to pair delta | 724.67 | yes; within 2000mil | 597.85999999999876 | yes; within 2000mil |  |  |  |  |  |  |  |  |  |  |
| PM8536 to GF of PEB |  |  |  | Card Edge Connector | Connector of PDPB to U.2 Connector (J5) |  |  |  |  | SFF-8639 Conn | SFF-8639 Conn | M.2 Conn |  |  |  |  |  |  |  |  |  |  |  |  |  |  |  |  |  |  |  |
| Net Name | PKG Lengths | PCB Net Length | Differential Match | The Length of Connector | Net Name | PCB Net Length | Differential Match | Total Length | Differential Match | Pin of Connector | Pin of Connector | Net Name | PCB Net Length | Differential Match | Total Length | Differential Match |  |  |  |  |  |  |  |  |  |  |  |  |  |  |  |
| PCIE_RX_N72 |  | 10366.69 |  |  | PE_RX1_DR5_P | 2407.2199999999998 |  | 12773.91 |  | E13 | E13 | D85_PCIE_A_RX0_N | 1244.06 |  | 14017.97 |  |  |  |  |  |  |  |  |  |  |  |  |  |  |  |  |
| PCIE_RX_P72 |  | 10365.92 | yes; within 1 mils |  | PE_RX1_DR5_N | 2407.0500000000002 | yes; within 1 mils | 12772.970000000001 | yes; within 5 mils | E14 | E14 | D85_PCIE_A_RX0_P | 1244.6500000000001 | yes; within 1 mils | 14017.62 | yes; within 5 mils |  |  |  |  |  |  |  |  |  |  |  |  |  |  |  |
| PCIE_RX_N73 |  | 10445.99 |  |  | PE_RX2_DR5_P | 2694.57 |  | 13140.56 |  | S20 | S20 | D85_PCIE_A_RX1_N | 1537.67 |  | 14678.23 |  |  |  |  |  |  |  |  |  |  |  |  |  |  |  |  |
| PCIE_RX_P73 |  | 10446.34 | yes; within 1 mils |  | PE_RX2_DR5_N | 2694.53 | yes; within 1 mils | 13140.87 | yes; within 5 mils | S21 | S21 | D85_PCIE_A_RX1_P | 1538.32 | yes; within 1 mils | 14679.19 | yes; within 5 mils |  |  |  |  |  |  |  |  |  |  |  |  |  |  |  |
|  | routing bundle delta | 80.420000000000073 |  |  | routing bundle delta | 287.52 | routing bundle delta | 367.89999999999964 | yes; within 600mil |  |  | routing bundle delta | 294.26 | routing bundle delta | 661.56999999999971 |  |  |  |  |  |  |  |  |  |  |  |  |  |  |  |  |
| PCIE_RX_N74 |  | 10617.87 |  |  | PE_RX3_DR5_P | 2707.31 |  | 13325.18 |  | S26 | S26 | D85_PCIE_B_RX0_N | 946.63 |  | 14271.81 |  |  |  |  |  |  |  |  |  |  |  |  |  |  |  |  |
| PCIE_RX_P74 |  | 10617.44 | yes; within 1 mils |  | PE_RX3_DR5_N | 2707.26 | yes; within 1 mils | 13324.7 | yes; within 5 mils | S27 | S27 | D85_PCIE_B_RX0_P | 947.24 | yes; within 1 mils | 14271.94 | yes; within 5 mils |  |  |  |  |  |  |  |  |  |  |  |  |  |  |  |
| PCIE_RX_N75 |  | 10724.36 |  |  | PE_RX4_DR5_P | 2727.8 |  | 13452.16 |  | E20 | E20 | D85_PCIE_B_RX1_N | 955.34 |  | 14407.5 |  |  |  |  |  |  |  |  |  |  |  |  |  |  |  |  |
| PCIE_RX_P75 |  | 10724.85 | yes; within 1 mils |  | PE_RX4_DR5_N | 2727.81 | yes; within 1 mils | 13452.66 | yes; within 5 mils | E21 | E21 | D85_PCIE_B_RX1_P | 955.96 | yes; within 1 mils | 14408.619999999999 | yes; within 5 mils |  |  |  |  |  |  |  |  |  |  |  |  |  |  |  |
|  | routing bundle delta | 107.40999999999985 |  |  | routing bundle delta | 20.549999999999727 | routing bundle delta | 127.95999999999913 | yes; within 600mil |  |  | routing bundle delta | 9.3300000000000409 | routing bundle delta | 136.80999999999949 |  |  |  |  |  |  |  |  |  |  |  |  |  |  |  |  |
|  | diff pair to pair delta | 358.93000000000029 | yes; within 2000mil |  | diff pair to pair delta | 320.75999999999976 | yes; within 2000mil | 679.68999999999869 | yes; within 2000mil |  |  | diff pair to pair delta | 591.68999999999994 | yes; within 2000mil | 661.56999999999971 | yes; within 2000mil |  |  |  |  |  |  |  |  |  |  |  |  |  |  |  |
| PM8536 to SSD10 |  |  |  |  |  |  |  |  |  |  |  |  |  |  | PCISLT68-14-GP-U | SKT-SAS28-P15-PCIE25-2-GP |  |  |  |  |  |  |  |  |  |  |  |  |  |  |  |
| PM8536 to GF of PEB |  |  |  |  |  |  |  |  | Card Edge Connector | Connector of PDPB to U.2 Connector (J10) |  |  |  |  | SFF-8639 Conn | SFF-8639 Conn | M.2 Conn |  |  |  |  |  |  |  |  |  |  |  |  |  |  |
| Net Name | PKG Lengths | PCB Net Length | Differential Match | Net Name | PCB Net Length | Differential Match | PEB Total Length | Differential Match | The Length of Connector | Net Name | PCB Net Length | Differential Match | Total Length | Differential Match | Pin of Connector | Pin of Connector | Net Name | PCB Net Length | Differential Match | Total Length | Differential Match |  |  |  |  |  |  |  |  |  |  |
| PCIE_TX_CAP_N64 |  | 8373.81 |  | PCIE_TX_N64 | 505.21 |  | 8879.0199999999986 |  |  | PE_TX1_DR10_P | 3700.77 |  | 12579.789999999999 |  | E10 | E10 | D85_PCIE_A_TX0_P | 1053.4100000000001 |  | 13633.199999999999 |  |  |  |  |  |  |  |  |  |  |  |
| PCIE_TX_CAP_P64 |  | 8373.36 | yes; within 1 mils | PCIE_TX_P64 | 505.2 | yes; within 1 mils | 8878.5600000000013 | yes; within 1 mils |  | PE_TX1_DR10_N | 3700.84 | yes; within 1 mils | 12579.400000000001 | yes; within 5 mils | E11 | E11 | D85_PCIE_A_TX0_N | 1053.3499999999999 | yes; within 1 mils | 13632.750000000002 | yes; within 5 mils |  |  |  |  |  |  |  |  |  |  |
| PCIE_TX_CAP_N65 |  | 8413.2900000000009 |  | PCIE_TX_N65 | 505.21 |  | 8918.5 |  |  | PE_TX2_DR10_P | 3154.31 |  | 12072.81 |  | S17 | S17 | D85_PCIE_A_TX1_P | 1230.57 |  | 13303.38 |  |  |  |  |  |  |  |  |  |  |  |
| PCIE_TX_CAP_P65 |  | 8414.16 | yes; within 1 mils | PCIE_TX_P65 | 505.21 | yes; within 1 mils | 8919.369999999999 | yes; within 1 mils |  | PE_TX2_DR10_N | 3154.16 | yes; within 1 mils | 12073.529999999999 | yes; within 5 mils | S18 | S18 | D85_PCIE_A_TX1_N | 1230.52 | yes; within 1 mils | 13304.05 | yes; within 5 mils |  |  |  |  |  |  |  |  |  |  |
|  |  |  |  |  |  | routing bundle delta | 40.809999999997672 |  |  | routing bundle delta | 546.68000000000029 | routing bundle delta | 506.97999999999956 | yes; within 600mil |  |  | routing bundle delta | 177.22000000000003 | routing bundle delta | 329.81999999999971 |  |  |  |  |  |  |  |  |  |  |  |
| PCIE_TX_CAP_N66 |  | 8575.93 |  | PCIE_TX_N66 | 505.21 |  | 9081.14 |  |  | PE_TX3_DR10_P | 2929.45 |  | 12010.59 |  | S23 | S23 | D85_PCIE_B_TX0_P | 505.9 |  | 12516.49 |  |  |  |  |  |  |  |  |  |  |  |
| PCIE_TX_CAP_P66 |  | 8576.7000000000007 | yes; within 1 mils | PCIE_TX_P66 | 505.2 | yes; within 1 mils | 9081.9000000000015 | yes; within 1 mils |  | PE_TX3_DR10_N | 2929.6 | yes; within 1 mils | 12011.500000000002 | yes; within 5 mils | S24 | S24 | D85_PCIE_B_TX0_N | 505.9 | yes; within 1 mils | 12517.400000000001 | yes; within 5 mils |  |  |  |  |  |  |  |  |  |  |
| PCIE_TX_CAP_N67 |  | 8648.5300000000007 |  | PCIE_TX_N67 | 505.21 |  | 9153.74 |  |  | PE_TX4_DR10_P | 2673.07 |  | 11826.81 |  | E17 | E17 | D85_PCIE_B_TX1_P | 536.89 |  | 12363.699999999999 |  |  |  |  |  |  |  |  |  |  |  |
| PCIE_TX_CAP_P67 |  | 8648.16 | yes; within 1 mils | PCIE_TX_P67 | 505.21 | yes; within 1 mils | 9153.369999999999 | yes; within 1 mils |  | PE_TX4_DR10_N | 2673.15 | yes; within 1 mils | 11826.519999999999 | yes; within 5 mils | E18 | E18 | D85_PCIE_B_TX1_N | 536.82000000000005 | yes; within 1 mils | 12363.339999999998 | yes; within 5 mils |  |  |  |  |  |  |  |  |  |  |
|  |  |  |  |  |  | routing bundle delta | 72.600000000000364 |  |  | routing bundle delta | 256.52999999999975 | routing bundle delta | 184.9800000000032 | yes; within 600mil |  |  | routing bundle delta | 30.990000000000009 | routing bundle delta | 154.06000000000313 |  |  |  |  |  |  |  |  |  |  |  |
|  |  |  |  |  |  | diff pair to pair delta | 275.17999999999847 | yes; within 2000mil |  | diff pair to pair delta | 1027.77 | yes; within 2000mil | 753.27000000000044 | yes; within 2000mil |  |  | diff pair to pair delta | 724.67 | yes; within 2000mil | 1269.8600000000006 | yes; within 2000mil |  |  |  |  |  |  |  |  |  |  |
| PM8536 to GF of PEB |  |  |  | Card Edge Connector | Connector of PDPB to U.2 Connector (J10) |  |  |  |  | SFF-8639 Conn | SFF-8639 Conn | M.2 Conn |  |  |  |  |  |  |  |  |  |  |  |  |  |  |  |  |  |  |  |
| Net Name | PKG Lengths | PCB Net Length | Differential Match | The Length of Connector | Net Name | PCB Net Length | Differential Match | Total Length | Differential Match | Pin of Connector | Pin of Connector | Net Name | PCB Net Length | Differential Match | Total Length | Differential Match |  |  |  |  |  |  |  |  |  |  |  |  |  |  |  |
| PCIE_RX_N64 |  | 9032.61 |  |  | PE_RX1_DR10_P | 3596.5 |  | 12629.11 |  | E13 | E13 | D85_PCIE_A_RX0_N | 1244.06 |  | 13873.17 |  |  |  |  |  |  |  |  |  |  |  |  |  |  |  |  |
| PCIE_RX_P64 |  | 9032.0499999999993 | yes; within 1 mils |  | PE_RX1_DR10_N | 3595.8 | yes; within 1 mils | 12627.849999999999 | yes; within 5 mils | E14 | E14 | D85_PCIE_A_RX0_P | 1244.6500000000001 | yes; within 1 mils | 13872.499999999998 | yes; within 5 mils |  |  |  |  |  |  |  |  |  |  |  |  |  |  |  |
| PCIE_RX_N65 |  | 9127.6299999999992 |  |  | PE_RX2_DR10_P | 3115.67 |  | 12243.3 |  | S20 | S20 | D85_PCIE_A_RX1_N | 1537.67 |  | 13780.97 |  |  |  |  |  |  |  |  |  |  |  |  |  |  |  |  |
| PCIE_RX_P65 |  | 9127.23 | yes; within 1 mils |  | PE_RX2_DR10_N | 3114.96 | yes; within 1 mils | 12242.189999999999 | yes; within 5 mils | S21 | S21 | D85_PCIE_A_RX1_P | 1538.32 | yes; within 1 mils | 13780.509999999998 | yes; within 5 mils |  |  |  |  |  |  |  |  |  |  |  |  |  |  |  |
|  | routing bundle delta | 95.579999999999927 |  |  | routing bundle delta | 481.53999999999996 | routing bundle delta | 386.92000000000189 | yes; within 600mil |  |  | routing bundle delta | 294.26 | routing bundle delta | 92.660000000001673 |  |  |  |  |  |  |  |  |  |  |  |  |  |  |  |  |
| PCIE_RX_N66 |  | 9285.89 |  |  | PE_RX3_DR10_P | 2852.88 |  | 12138.77 |  | S26 | S26 | D85_PCIE_B_RX0_N | 946.63 |  | 13085.4 |  |  |  |  |  |  |  |  |  |  |  |  |  |  |  |  |
| PCIE_RX_P66 |  | 9286.2099999999991 | yes; within 1 mils |  | PE_RX3_DR10_N | 2852.29 | yes; within 1 mils | 12138.5 | yes; within 5 mils | S27 | S27 | D85_PCIE_B_RX0_P | 947.24 | yes; within 1 mils | 13085.74 | yes; within 5 mils |  |  |  |  |  |  |  |  |  |  |  |  |  |  |  |
| PCIE_RX_N67 |  | 9382.23 |  |  | PE_RX4_DR10_P | 2675.78 |  | 12058.01 |  | E20 | E20 | D85_PCIE_B_RX1_N | 955.34 |  | 13013.35 |  |  |  |  |  |  |  |  |  |  |  |  |  |  |  |  |
| PCIE_RX_P67 |  | 9383.01 | yes; within 1 mils |  | PE_RX4_DR10_N | 2675.15 | yes; within 1 mils | 12058.16 | yes; within 5 mils | E21 | E21 | D85_PCIE_B_RX1_P | 955.96 | yes; within 1 mils | 13014.119999999999 | yes; within 5 mils |  |  |  |  |  |  |  |  |  |  |  |  |  |  |  |
|  | routing bundle delta | 97.1200000000008 |  |  | routing bundle delta | 177.73000000000002 | routing bundle delta | 80.760000000000218 | yes; within 600mil |  |  | routing bundle delta | 9.3300000000000409 | routing bundle delta | 72.389999999999418 |  |  |  |  |  |  |  |  |  |  |  |  |  |  |  |  |
|  | diff pair to pair delta | 350.96000000000095 | yes; within 2000mil |  | diff pair to pair delta | 921.34999999999991 | yes; within 2000mil | 571.10000000000036 | yes; within 2000mil |  |  | diff pair to pair delta | 591.68999999999994 | yes; within 2000mil | 859.81999999999971 | yes; within 2000mil |  |  |  |  |  |  |  |  |  |  |  |  |  |  |  |
| PM8536 to SSD1 |  |  |  |  |  |  |  |  |  |  |  |  |  |  | PCISLT68-14-GP-U | SKT-SAS28-P15-PCIE25-2-GP |  |  |  |  |  |  |  |  |  |  |  |  |  |  |  |
| PM8536 to GF of PEB |  |  |  |  |  |  |  |  | Card Edge Connector | Connector of PDPB to U.2 Connector (J1) |  |  |  |  | SFF-8639 Conn | SFF-8639 Conn | M.2 Conn |  |  |  |  |  |  |  |  |  |  |  |  |  |  |
| Net Name | PKG Lengths | PCB Net Length | Differential Match | Net Name | PCB Net Length | Differential Match | PEB Total Length | Differential Match | The Length of Connector | Net Name | PCB Net Length | Differential Match | Total Length | Differential Match | Pin of Connector | Pin of Connector | Net Name | PCB Net Length | Differential Match | Total Length | Differential Match |  |  |  |  |  |  |  |  |  |  |
| PCIE_TX_CAP_N60 |  | 7800.63 |  | PCIE_TX_N60 | 505.21 |  | 8305.84 |  |  | PE_TX1_DR1_N | 9310.35 |  | 17616.190000000002 |  | E10 | E10 | D85_PCIE_A_TX0_P | 1053.4100000000001 |  | 18669.600000000002 |  |  |  |  |  |  |  |  |  |  |  |
| PCIE_TX_CAP_P60 |  | 7801.25 | yes; within 1 mils | PCIE_TX_P60 | 505.21 | yes; within 1 mils | 8306.4599999999991 | yes; within 1 mils |  | PE_TX1_DR1_P | 9310.06 | yes; within 1 mils | 17616.519999999997 | yes; within 5 mils | E11 | E11 | D85_PCIE_A_TX0_N | 1053.3499999999999 | yes; within 1 mils | 18669.869999999995 | yes; within 5 mils |  |  |  |  |  |  |  |  |  |  |
| PCIE_TX_CAP_N61 |  | 7784.61 |  | PCIE_TX_N61 | 505.21 |  | 8289.82 |  |  | PE_TX2_DR1_N | 9071.08 |  | 17360.900000000001 |  | S17 | S17 | D85_PCIE_A_TX1_P | 1230.57 |  | 18591.47 |  |  |  |  |  |  |  |  |  |  |  |
| PCIE_TX_CAP_P61 |  | 7783.84 | yes; within 1 mils | PCIE_TX_P61 | 505.21 | yes; within 1 mils | 8289.0499999999993 | yes; within 1 mils |  | PE_TX2_DR1_P | 9071.1 | yes; within 1 mils | 17360.150000000001 | yes; within 5 mils | S18 | S18 | D85_PCIE_A_TX1_N | 1230.52 | yes; within 1 mils | 18590.670000000002 | yes; within 5 mils |  |  |  |  |  |  |  |  |  |  |
|  |  |  |  |  |  | routing bundle delta | 17.409999999999854 |  |  | routing bundle delta | 239.27000000000044 | routing bundle delta | 256.36999999999534 | yes; within 600mil |  |  | routing bundle delta | 177.22000000000003 | routing bundle delta | 79.199999999993452 |  |  |  |  |  |  |  |  |  |  |  |
| PCIE_TX_CAP_N62 |  | 7868.84 |  | PCIE_TX_N62 | 505.21 |  | 8374.0499999999993 |  |  | PE_TX3_DR1_N | 9008.67 |  | 17382.72 |  | S23 | S23 | D85_PCIE_B_TX0_P | 505.9 |  | 17888.620000000003 |  |  |  |  |  |  |  |  |  |  |  |
| PCIE_TX_CAP_P62 |  | 7868.93 | yes; within 1 mils | PCIE_TX_P62 | 505.21 | yes; within 1 mils | 8374.14 | yes; within 1 mils |  | PE_TX3_DR1_P | 9008.66 | yes; within 1 mils | 17382.8 | yes; within 5 mils | S24 | S24 | D85_PCIE_B_TX0_N | 505.9 | yes; within 1 mils | 17888.7 | yes; within 5 mils |  |  |  |  |  |  |  |  |  |  |
| PCIE_TX_CAP_N63 |  | 7908.67 |  | PCIE_TX_N63 | 505.21 |  | 8413.8799999999992 |  |  | PE_TX4_DR1_N | 8974.0400000000009 |  | 17387.919999999998 |  | E17 | E17 | D85_PCIE_B_TX1_P | 536.89 |  | 17924.809999999998 |  |  |  |  |  |  |  |  |  |  |  |
| PCIE_TX_CAP_P63 |  | 7909.19 | yes; within 1 mils | PCIE_TX_P63 | 505.21 | yes; within 1 mils | 8414.4 | yes; within 1 mils |  | PE_TX4_DR1_P | 8974.0400000000009 | yes; within 1 mils | 17388.440000000002 | yes; within 5 mils | E18 | E18 | D85_PCIE_B_TX1_N | 536.82000000000005 | yes; within 1 mils | 17925.260000000002 | yes; within 5 mils |  |  |  |  |  |  |  |  |  |  |
|  |  |  |  |  |  | routing bundle delta | 40.350000000000364 |  |  | routing bundle delta | 34.6299999999992 | routing bundle delta | 5.7200000000011642 | yes; within 600mil |  |  | routing bundle delta | 30.990000000000009 | routing bundle delta | 36.639999999999418 |  |  |  |  |  |  |  |  |  |  |  |
|  |  |  |  |  |  | diff pair to pair delta | 125.35000000000036 | yes; within 2000mil |  | diff pair to pair delta | 336.30999999999949 | yes; within 2000mil | 256.36999999999534 | yes; within 2000mil |  |  | diff pair to pair delta | 724.67 | yes; within 2000mil | 781.24999999999272 | yes; within 2000mil |  |  |  |  |  |  |  |  |  |  |
| PM8536 to GF of PEB |  |  |  | Card Edge Connector | Connector of PDPB to U.2 Connector (J1) |  |  |  |  | SFF-8639 Conn | SFF-8639 Conn | M.2 Conn |  |  |  |  |  |  |  |  |  |  |  |  |  |  |  |  |  |  |  |
| Net Name | PKG Lengths | PCB Net Length | Differential Match | The Length of Connector | Net Name | PCB Net Length | Differential Match | Total Length | Differential Match | Pin of Connector | Pin of Connector | Net Name | PCB Net Length | Differential Match | Total Length | Differential Match |  |  |  |  |  |  |  |  |  |  |  |  |  |  |  |
| PCIE_RX_N60 |  | 8536.32 |  |  | PE_RX1_DR1_N | 9224.75 |  | 17761.07 |  | E13 | E13 | D85_PCIE_A_RX0_N | 1244.06 |  | 19005.13 |  |  |  |  |  |  |  |  |  |  |  |  |  |  |  |  |
| PCIE_RX_P60 |  | 8535.57 | yes; within 1 mils |  | PE_RX1_DR1_P | 9224.4699999999993 | yes; within 1 mils | 17760.04 | yes; within 5 mils | E14 | E14 | D85_PCIE_A_RX0_P | 1244.6500000000001 | yes; within 1 mils | 19004.690000000002 | yes; within 5 mils |  |  |  |  |  |  |  |  |  |  |  |  |  |  |  |
| PCIE_RX_N61 |  | 8530.83 |  |  | PE_RX2_DR1_N | 9035.0400000000009 |  | 17565.870000000003 |  | S20 | S20 | D85_PCIE_A_RX1_N | 1537.67 |  | 19103.54 |  |  |  |  |  |  |  |  |  |  |  |  |  |  |  |  |
| PCIE_RX_P61 |  | 8530.02 | yes; within 1 mils |  | PE_RX2_DR1_P | 9034.94 | yes; within 1 mils | 17564.96 | yes; within 5 mils | S21 | S21 | D85_PCIE_A_RX1_P | 1538.32 | yes; within 1 mils | 19103.28 | yes; within 5 mils |  |  |  |  |  |  |  |  |  |  |  |  |  |  |  |
|  | routing bundle delta | 6.2999999999992724 |  |  | routing bundle delta | 189.80999999999949 | routing bundle delta | 196.11000000000058 | yes; within 600mil |  |  | routing bundle delta | 294.26 | routing bundle delta | 98.849999999998545 |  |  |  |  |  |  |  |  |  |  |  |  |  |  |  |  |
| PCIE_RX_N62 |  | 8616.73 |  |  | PE_RX3_DR1_N | 9000.83 |  | 17617.559999999998 |  | S26 | S26 | D85_PCIE_B_RX0_N | 946.63 |  | 18564.189999999999 |  |  |  |  |  |  |  |  |  |  |  |  |  |  |  |  |
| PCIE_RX_P62 |  | 8616.52 | yes; within 1 mils |  | PE_RX3_DR1_P | 9000.7999999999993 | yes; within 1 mils | 17617.32 | yes; within 5 mils | S27 | S27 | D85_PCIE_B_RX0_P | 947.24 | yes; within 1 mils | 18564.560000000001 | yes; within 5 mils |  |  |  |  |  |  |  |  |  |  |  |  |  |  |  |
| PCIE_RX_N63 |  | 8644.6200000000008 |  |  | PE_RX4_DR1_N | 8966.26 |  | 17610.88 |  | E20 | E20 | D85_PCIE_B_RX1_N | 955.34 |  | 18566.22 |  |  |  |  |  |  |  |  |  |  |  |  |  |  |  |  |
| PCIE_RX_P63 |  | 8644.06 | yes; within 1 mils |  | PE_RX4_DR1_P | 8966.25 | yes; within 1 mils | 17610.309999999998 | yes; within 5 mils | E21 | E21 | D85_PCIE_B_RX1_P | 955.96 | yes; within 1 mils | 18566.269999999997 | yes; within 5 mils |  |  |  |  |  |  |  |  |  |  |  |  |  |  |  |
|  | routing bundle delta | 28.100000000000364 |  |  | routing bundle delta | 34.579999999999927 | routing bundle delta | 7.25 | yes; within 600mil |  |  | routing bundle delta | 9.3300000000000409 | routing bundle delta | 2.0799999999981083 |  |  |  |  |  |  |  |  |  |  |  |  |  |  |  |  |
|  | diff pair to pair delta | 114.60000000000036 | yes; within 2000mil |  | diff pair to pair delta | 258.5 | yes; within 2000mil | 196.11000000000058 | yes; within 2000mil |  |  | diff pair to pair delta | 591.68999999999994 | yes; within 2000mil | 539.35000000000218 | yes; within 2000mil |  |  |  |  |  |  |  |  |  |  |  |  |  |  |  |
| PM8536 to SSD6 |  |  |  |  |  |  |  |  |  |  |  |  |  |  | PCISLT68-14-GP-U | SKT-SAS28-P15-PCIE25-2-GP |  |  |  |  |  |  |  |  |  |  |  |  |  |  |  |
| PM8536 to GF of PEB |  |  |  |  |  |  |  |  | Card Edge Connector | Connector of PDPB to U.2 Connector (J6) |  |  |  |  | SFF-8639 Conn | SFF-8639 Conn | M.2 Conn |  |  |  |  |  |  |  |  |  |  |  |  |  |  |
| Net Name | PKG Lengths | PCB Net Length | Differential Match | Net Name | PCB Net Length | Differential Match | PEB Total Length | Differential Match | The Length of Connector | Net Name | PCB Net Length | Differential Match | Total Length | Differential Match | Pin of Connector | Pin of Connector | Net Name | PCB Net Length | Differential Match | Total Length | Differential Match |  |  |  |  |  |  |  |  |  |  |
| PCIE_TX_CAP_N56 |  | 6965.94 |  | PCIE_TX_N56 | 505.21 |  | 7471.15 |  |  | PE_TX1_DR6_N | 1791.55 |  | 9262.6999999999989 |  | E10 | E10 | D85_PCIE_A_TX0_P | 1053.4100000000001 |  | 10316.109999999999 |  |  |  |  |  |  |  |  |  |  |  |
| PCIE_TX_CAP_P56 |  | 6965.17 | yes; within 1 mils | PCIE_TX_P56 | 505.21 | yes; within 1 mils | 7470.38 | yes; within 1 mils |  | PE_TX1_DR6_P | 1791.56 | yes; within 1 mils | 9261.94 | yes; within 5 mils | E11 | E11 | D85_PCIE_A_TX0_N | 1053.3499999999999 | yes; within 1 mils | 10315.290000000001 | yes; within 5 mils |  |  |  |  |  |  |  |  |  |  |
| PCIE_TX_CAP_N57 |  | 6972.05 |  | PCIE_TX_N57 | 505.21 |  | 7477.26 |  |  | PE_TX2_DR6_N | 2419.59 |  | 9896.85 |  | S17 | S17 | D85_PCIE_A_TX1_P | 1230.57 |  | 11127.42 |  |  |  |  |  |  |  |  |  |  |  |
| PCIE_TX_CAP_P57 |  | 6971.8 | yes; within 1 mils | PCIE_TX_P57 | 505.21 | yes; within 1 mils | 7477.01 | yes; within 1 mils |  | PE_TX2_DR6_P | 2419.65 | yes; within 1 mils | 9896.66 | yes; within 5 mils | S18 | S18 | D85_PCIE_A_TX1_N | 1230.52 | yes; within 1 mils | 11127.18 | yes; within 5 mils |  |  |  |  |  |  |  |  |  |  |
|  |  |  |  |  |  | routing bundle delta | 6.8800000000001091 |  |  | routing bundle delta | 628.10000000000014 | routing bundle delta | 634.90999999999985 | no; exceed 600mil |  |  | routing bundle delta | 177.22000000000003 | routing bundle delta | 812.1299999999992 |  |  |  |  |  |  |  |  |  |  |  |
| PCIE_TX_CAP_N58 |  | 7048.35 |  | PCIE_TX_N58 | 505.21 |  | 7553.56 |  |  | PE_TX3_DR6_N | 2301.71 |  | 9855.27 |  | S23 | S23 | D85_PCIE_B_TX0_P | 505.9 |  | 10361.17 |  |  |  |  |  |  |  |  |  |  |  |
| PCIE_TX_CAP_P58 |  | 7047.69 | yes; within 1 mils | PCIE_TX_P58 | 505.22 | yes; within 1 mils | 7552.91 | yes; within 1 mils |  | PE_TX3_DR6_P | 2301.71 | yes; within 1 mils | 9854.619999999999 | yes; within 5 mils | S24 | S24 | D85_PCIE_B_TX0_N | 505.9 | yes; within 1 mils | 10360.519999999999 | yes; within 5 mils |  |  |  |  |  |  |  |  |  |  |
| PCIE_TX_CAP_N59 |  | 7046.47 |  | PCIE_TX_N59 | 505.21 |  | 7551.68 |  |  | PE_TX4_DR6_N | 2244.44 |  | 9796.1200000000008 |  | E17 | E17 | D85_PCIE_B_TX1_P | 536.89 |  | 10333.01 |  |  |  |  |  |  |  |  |  |  |  |
| PCIE_TX_CAP_P59 |  | 7045.63 | yes; within 1 mils | PCIE_TX_P59 | 505.21 | yes; within 1 mils | 7550.84 | yes; within 1 mils |  | PE_TX4_DR6_P | 2244.4299999999998 | yes; within 1 mils | 9795.27 | yes; within 5 mils | E18 | E18 | D85_PCIE_B_TX1_N | 536.82000000000005 | yes; within 1 mils | 10332.09 | yes; within 5 mils |  |  |  |  |  |  |  |  |  |  |
|  |  |  |  |  |  | routing bundle delta | 2.7200000000002547 |  |  | routing bundle delta | 57.2800000000002 | routing bundle delta | 60 | yes; within 600mil |  |  | routing bundle delta | 30.990000000000009 | routing bundle delta | 29.079999999999927 |  |  |  |  |  |  |  |  |  |  |  |
|  |  |  |  |  |  | diff pair to pair delta | 83.180000000000291 | yes; within 2000mil |  | diff pair to pair delta | 628.10000000000014 | yes; within 2000mil | 634.90999999999985 | yes; within 2000mil |  |  | diff pair to pair delta | 724.67 | yes; within 2000mil | 812.1299999999992 | yes; within 2000mil |  |  |  |  |  |  |  |  |  |  |
| PM8536 to GF of PEB |  |  |  | Card Edge Connector | Connector of PDPB to U.2 Connector (J6) |  |  |  |  | SFF-8639 Conn | SFF-8639 Conn | M.2 Conn |  |  |  |  |  |  |  |  |  |  |  |  |  |  |  |  |  |  |  |
| Net Name | PKG Lengths | PCB Net Length | Differential Match | The Length of Connector | Net Name | PCB Net Length | Differential Match | Total Length | Differential Match | Pin of Connector | Pin of Connector | Net Name | PCB Net Length | Differential Match | Total Length | Differential Match |  |  |  |  |  |  |  |  |  |  |  |  |  |  |  |
| PCIE_RX_N56 |  | 7650.45 |  |  | PE_RX1_DR6_N | 1778.96 |  | 9429.41 |  | E13 | E13 | D85_PCIE_A_RX0_N | 1244.06 |  | 10673.47 |  |  |  |  |  |  |  |  |  |  |  |  |  |  |  |  |
| PCIE_RX_P56 |  | 7650.5 | yes; within 1 mils |  | PE_RX1_DR6_P | 1778.93 | yes; within 1 mils | 9429.43 | yes; within 5 mils | E14 | E14 | D85_PCIE_A_RX0_P | 1244.6500000000001 | yes; within 1 mils | 10674.08 | yes; within 5 mils |  |  |  |  |  |  |  |  |  |  |  |  |  |  |  |
| PCIE_RX_N57 |  | 7531.65 |  |  | PE_RX2_DR6_N | 2316.02 |  | 9847.67 |  | S20 | S20 | D85_PCIE_A_RX1_N | 1537.67 |  | 11385.34 |  |  |  |  |  |  |  |  |  |  |  |  |  |  |  |  |
| PCIE_RX_P57 |  | 7532.51 | yes; within 1 mils |  | PE_RX2_DR6_P | 2316.0300000000002 | yes; within 1 mils | 9848.5400000000009 | yes; within 5 mils | S21 | S21 | D85_PCIE_A_RX1_P | 1538.32 | yes; within 1 mils | 11386.86 | yes; within 5 mils |  |  |  |  |  |  |  |  |  |  |  |  |  |  |  |
|  | routing bundle delta | 118.85000000000036 |  |  | routing bundle delta | 537.10000000000014 | routing bundle delta | 419.13000000000102 | yes; within 600mil |  |  | routing bundle delta | 294.26 | routing bundle delta | 713.39000000000124 |  |  |  |  |  |  |  |  |  |  |  |  |  |  |  |  |
| PCIE_RX_N58 |  | 7599.62 |  |  | PE_RX3_DR6_N | 2268.5700000000002 |  | 9868.19 |  | S26 | S26 | D85_PCIE_B_RX0_N | 946.63 |  | 10814.82 |  |  |  |  |  |  |  |  |  |  |  |  |  |  |  |  |
| PCIE_RX_P58 |  | 7600.38 | yes; within 1 mils |  | PE_RX3_DR6_P | 2268.5500000000002 | yes; within 1 mils | 9868.93 | yes; within 5 mils | S27 | S27 | D85_PCIE_B_RX0_P | 947.24 | yes; within 1 mils | 10816.17 | yes; within 5 mils |  |  |  |  |  |  |  |  |  |  |  |  |  |  |  |
| PCIE_RX_N59 |  | 7595.72 |  |  | PE_RX4_DR6_N | 2203.2800000000002 |  | 9799 |  | E20 | E20 | D85_PCIE_B_RX1_N | 955.34 |  | 10754.34 |  |  |  |  |  |  |  |  |  |  |  |  |  |  |  |  |
| PCIE_RX_P59 |  | 7595.03 | yes; within 1 mils |  | PE_RX4_DR6_P | 2203.2800000000002 | yes; within 1 mils | 9798.31 | yes; within 5 mils | E21 | E21 | D85_PCIE_B_RX1_P | 955.96 | yes; within 1 mils | 10754.27 | yes; within 5 mils |  |  |  |  |  |  |  |  |  |  |  |  |  |  |  |
|  | routing bundle delta | 5.3500000000003638 |  |  | routing bundle delta | 65.289999999999964 | routing bundle delta | 70.6200000000008 | yes; within 600mil |  |  | routing bundle delta | 9.3300000000000409 | routing bundle delta | 61.899999999999636 |  |  |  |  |  |  |  |  |  |  |  |  |  |  |  |  |
|  | diff pair to pair delta | 118.85000000000036 | yes; within 2000mil |  | diff pair to pair delta | 537.10000000000014 | yes; within 2000mil | 439.52000000000044 | yes; within 2000mil |  |  | diff pair to pair delta | 591.68999999999994 | yes; within 2000mil | 713.39000000000124 | yes; within 2000mil |  |  |  |  |  |  |  |  |  |  |  |  |  |  |  |
| PM8536 to SSD11 |  |  |  |  |  |  |  |  |  |  |  |  |  |  | PCISLT68-14-GP-U | SKT-SAS28-P15-PCIE25-2-GP |  |  |  |  |  |  |  |  |  |  |  |  |  |  |  |
| PM8536 to GF of PEB |  |  |  |  |  |  |  |  | Card Edge Connector | Connector of PDPB to U.2 Connector (J11) |  |  |  |  | SFF-8639 Conn | SFF-8639 Conn | M.2 Conn |  |  |  |  |  |  |  |  |  |  |  |  |  |  |
| Net Name | PKG Lengths | PCB Net Length | Differential Match | Net Name | PCB Net Length | Differential Match | PEB Total Length | Differential Match | The Length of Connector | Net Name | PCB Net Length | Differential Match | Total Length | Differential Match | Pin of Connector | Pin of Connector | Net Name | PCB Net Length | Differential Match | Total Length | Differential Match |  |  |  |  |  |  |  |  |  |  |
| PCIE_TX_CAP_N52 |  | 6815.77 |  | PCIE_TX_N52 | 505.21 |  | 7320.9800000000005 |  |  | PE_TX1_DR11_N | 1770.02 |  | 9091 |  | E10 | E10 | D85_PCIE_A_TX0_P | 1053.4100000000001 |  | 10144.41 |  |  |  |  |  |  |  |  |  |  |  |
| PCIE_TX_CAP_P52 |  | 6815.97 | yes; within 1 mils | PCIE_TX_P52 | 505.21 | yes; within 1 mils | 7321.18 | yes; within 1 mils |  | PE_TX1_DR11_P | 1770.09 | yes; within 1 mils | 9091.27 | yes; within 5 mils | E11 | E11 | D85_PCIE_A_TX0_N | 1053.3499999999999 | yes; within 1 mils | 10144.620000000001 | yes; within 5 mils |  |  |  |  |  |  |  |  |  |  |
| PCIE_TX_CAP_N53 |  | 6822.61 |  | PCIE_TX_N53 | 505.21 |  | 7327.82 |  |  | PE_TX2_DR11_N | 2296.17 |  | 9623.99 |  | S17 | S17 | D85_PCIE_A_TX1_P | 1230.57 |  | 10854.56 |  |  |  |  |  |  |  |  |  |  |  |
| PCIE_TX_CAP_P53 |  | 6822.24 | yes; within 1 mils | PCIE_TX_P53 | 505.21 | yes; within 1 mils | 7327.45 | yes; within 1 mils |  | PE_TX2_DR11_P | 2296.29 | yes; within 1 mils | 9623.74 | yes; within 5 mils | S18 | S18 | D85_PCIE_A_TX1_N | 1230.52 | yes; within 1 mils | 10854.26 | yes; within 5 mils |  |  |  |  |  |  |  |  |  |  |
|  |  |  |  |  |  | routing bundle delta | 6.839999999999236 |  |  | routing bundle delta | 526.27 | routing bundle delta | 532.98999999999978 | yes; within 600mil |  |  | routing bundle delta | 177.22000000000003 | routing bundle delta | 710.14999999999964 |  |  |  |  |  |  |  |  |  |  |  |
| PCIE_TX_CAP_N54 |  | 6937.64 |  | PCIE_TX_N54 | 505.21 |  | 7442.85 |  |  | PE_TX3_DR11_N | 2657.73 |  | 10100.58 |  | S23 | S23 | D85_PCIE_B_TX0_P | 505.9 |  | 10606.48 |  |  |  |  |  |  |  |  |  |  |  |
| PCIE_TX_CAP_P54 |  | 6937.12 | yes; within 1 mils | PCIE_TX_P54 | 505.21 | yes; within 1 mils | 7442.33 | yes; within 1 mils |  | PE_TX3_DR11_P | 2657.78 | yes; within 1 mils | 10100.11 | yes; within 5 mils | S24 | S24 | D85_PCIE_B_TX0_N | 505.9 | yes; within 1 mils | 10606.01 | yes; within 5 mils |  |  |  |  |  |  |  |  |  |  |
| PCIE_TX_CAP_N55 |  | 6909.65 |  | PCIE_TX_N55 | 505.21 |  | 7414.86 |  |  | PE_TX4_DR11_N | 2957.11 |  | 10371.969999999999 |  | E17 | E17 | D85_PCIE_B_TX1_P | 536.89 |  | 10908.859999999999 |  |  |  |  |  |  |  |  |  |  |  |
| PCIE_TX_CAP_P55 |  | 6908.91 | yes; within 1 mils | PCIE_TX_P55 | 505.21 | yes; within 1 mils | 7414.12 | yes; within 1 mils |  | PE_TX4_DR11_P | 2956.79 | yes; within 1 mils | 10370.91 | yes; within 5 mils | E18 | E18 | D85_PCIE_B_TX1_N | 536.82000000000005 | yes; within 1 mils | 10907.73 | yes; within 5 mils |  |  |  |  |  |  |  |  |  |  |
|  |  |  |  |  |  | routing bundle delta | 28.730000000000473 |  |  | routing bundle delta | 299.38000000000011 | routing bundle delta | 271.85999999999876 | yes; within 600mil |  |  | routing bundle delta | 30.990000000000009 | routing bundle delta | 302.84999999999854 |  |  |  |  |  |  |  |  |  |  |  |
|  |  |  |  |  |  | diff pair to pair delta | 121.86999999999989 | yes; within 2000mil |  | diff pair to pair delta | 1187.0900000000001 | yes; within 2000mil | 1280.9699999999993 | yes; within 2000mil |  |  | diff pair to pair delta | 724.67 | yes; within 2000mil | 764.44999999999891 | yes; within 2000mil |  |  |  |  |  |  |  |  |  |  |
| PM8536 to GF of PEB |  |  |  | Card Edge Connector | Connector of PDPB to U.2 Connector (J11) |  |  |  |  | SFF-8639 Conn | SFF-8639 Conn | M.2 Conn |  |  |  |  |  |  |  |  |  |  |  |  |  |  |  |  |  |  |  |
| Net Name | PKG Lengths | PCB Net Length | Differential Match | The Length of Connector | Net Name | PCB Net Length | Differential Match | Total Length | Differential Match | Pin of Connector | Pin of Connector | Net Name | PCB Net Length | Differential Match | Total Length | Differential Match |  |  |  |  |  |  |  |  |  |  |  |  |  |  |  |
| PCIE_RX_N52 |  | 7521.85 |  |  | PE_RX1_DR11_N | 1362.03 |  | 8883.880000000001 |  | E13 | E13 | D85_PCIE_A_RX0_N | 1244.06 |  | 10127.94 |  |  |  |  |  |  |  |  |  |  |  |  |  |  |  |  |
| PCIE_RX_P52 |  | 7521.64 | yes; within 1 mils |  | PE_RX1_DR11_P | 1361.43 | yes; within 1 mils | 8883.07 | yes; within 5 mils | E14 | E14 | D85_PCIE_A_RX0_P | 1244.6500000000001 | yes; within 1 mils | 10127.719999999999 | yes; within 5 mils |  |  |  |  |  |  |  |  |  |  |  |  |  |  |  |
| PCIE_RX_N53 |  | 7456.64 |  |  | PE_RX2_DR11_N | 2302.9699999999998 |  | 9759.61 |  | S20 | S20 | D85_PCIE_A_RX1_N | 1537.67 |  | 11297.28 |  |  |  |  |  |  |  |  |  |  |  |  |  |  |  |  |
| PCIE_RX_P53 |  | 7456.54 | yes; within 1 mils |  | PE_RX2_DR11_P | 2303.58 | yes; within 1 mils | 9760.119999999999 | yes; within 5 mils | S21 | S21 | D85_PCIE_A_RX1_P | 1538.32 | yes; within 1 mils | 11298.439999999999 | yes; within 5 mils |  |  |  |  |  |  |  |  |  |  |  |  |  |  |  |
|  | routing bundle delta | 65.3100000000004 |  |  | routing bundle delta | 942.14999999999986 | routing bundle delta | 877.04999999999927 | no; exceed 600mil |  |  | routing bundle delta | 294.26 | routing bundle delta | 1170.7199999999993 |  |  |  |  |  |  |  |  |  |  |  |  |  |  |  |  |
| PCIE_RX_N54 |  | 7542.08 |  |  | PE_RX3_DR11_N | 2635.88 |  | 10177.959999999999 |  | S26 | S26 | D85_PCIE_B_RX0_N | 946.63 |  | 11124.589999999998 |  |  |  |  |  |  |  |  |  |  |  |  |  |  |  |  |
| PCIE_RX_P54 |  | 7542.24 | yes; within 1 mils |  | PE_RX3_DR11_P | 2636.62 | yes; within 1 mils | 10178.86 | yes; within 5 mils | S27 | S27 | D85_PCIE_B_RX0_P | 947.24 | yes; within 1 mils | 11126.1 | yes; within 5 mils |  |  |  |  |  |  |  |  |  |  |  |  |  |  |  |
| PCIE_RX_N55 |  | 7503.53 |  |  | PE_RX4_DR11_N | 2959.34 |  | 10462.869999999999 |  | E20 | E20 | D85_PCIE_B_RX1_N | 955.34 |  | 11418.21 |  |  |  |  |  |  |  |  |  |  |  |  |  |  |  |  |
| PCIE_RX_P55 |  | 7504.21 | yes; within 1 mils |  | PE_RX4_DR11_P | 2960.07 | yes; within 1 mils | 10464.280000000001 | yes; within 5 mils | E21 | E21 | D85_PCIE_B_RX1_P | 955.96 | yes; within 1 mils | 11420.240000000002 | yes; within 5 mils |  |  |  |  |  |  |  |  |  |  |  |  |  |  |  |
|  | routing bundle delta | 38.710000000000036 |  |  | routing bundle delta | 324.19000000000005 | routing bundle delta | 286.32000000000153 | yes; within 600mil |  |  | routing bundle delta | 9.3300000000000409 | routing bundle delta | 295.65000000000327 |  |  |  |  |  |  |  |  |  |  |  |  |  |  |  |  |
|  | diff pair to pair delta | 85.699999999999818 | yes; within 2000mil |  | diff pair to pair delta | 1598.64 | yes; within 2000mil | 1581.2100000000009 | yes; within 2000mil |  |  | diff pair to pair delta | 591.68999999999994 | yes; within 2000mil | 1292.5200000000023 | yes; within 2000mil |  |  |  |  |  |  |  |  |  |  |  |  |  |  |  |
| PM8536 to SSD2 |  |  |  |  |  |  |  |  |  |  |  |  |  |  | PCISLT68-14-GP-U | SKT-SAS28-P15-PCIE25-2-GP |  |  |  |  |  |  |  |  |  |  |  |  |  |  |  |
| PM8536 to GF of PEB |  |  |  |  |  |  |  |  | Card Edge Connector | Connector of PDPB to U.2 Connector (J2) |  |  |  |  | SFF-8639 Conn | SFF-8639 Conn | M.2 Conn |  |  |  |  |  |  |  |  |  |  |  |  |  |  |
| Net Name | PKG Lengths | PCB Net Length | Differential Match | Net Name | PCB Net Length | Differential Match | PEB Total Length | Differential Match | The Length of Connector | Net Name | PCB Net Length | Differential Match | Total Length | Differential Match | Pin of Connector | Pin of Connector | Net Name | PCB Net Length | Differential Match | Total Length | Differential Match |  |  |  |  |  |  |  |  |  |  |
| PCIE_TX_CAP_N48 |  | 6665.84 |  | PCIE_TX_N48 | 505.21 |  | 7171.05 |  |  | PE_TX1_DR2_N | 9469.5 |  | 16640.55 |  | E10 | E10 | D85_PCIE_A_TX0_P | 1053.4100000000001 |  | 17693.96 |  |  |  |  |  |  |  |  |  |  |  |
| PCIE_TX_CAP_P48 |  | 6665.02 | yes; within 1 mils | PCIE_TX_P48 | 505.2 | yes; within 1 mils | 7170.22 | yes; within 1 mils |  | PE_TX1_DR2_P | 9469.5 | yes; within 1 mils | 16639.72 | yes; within 5 mils | E11 | E11 | D85_PCIE_A_TX0_N | 1053.3499999999999 | yes; within 1 mils | 17693.07 | yes; within 5 mils |  |  |  |  |  |  |  |  |  |  |
| PCIE_TX_CAP_N49 |  | 6652.62 |  | PCIE_TX_N49 | 505.21 |  | 7157.83 |  |  | PE_TX2_DR2_N | 9545.4699999999993 |  | 16703.3 |  | S17 | S17 | D85_PCIE_A_TX1_P | 1230.57 |  | 17933.87 |  |  |  |  |  |  |  |  |  |  |  |
| PCIE_TX_CAP_P49 |  | 6652.18 | yes; within 1 mils | PCIE_TX_P49 | 505.21 | yes; within 1 mils | 7157.39 | yes; within 1 mils |  | PE_TX2_DR2_P | 9545.4500000000007 | yes; within 1 mils | 16702.84 | yes; within 5 mils | S18 | S18 | D85_PCIE_A_TX1_N | 1230.52 | yes; within 1 mils | 17933.36 | yes; within 5 mils |  |  |  |  |  |  |  |  |  |  |
|  |  |  |  |  |  | routing bundle delta | 13.659999999999854 |  |  | routing bundle delta | 75.969999999999345 | routing bundle delta | 63.579999999998108 | yes; within 600mil |  |  | routing bundle delta | 177.22000000000003 | routing bundle delta | 240.79999999999927 |  |  |  |  |  |  |  |  |  |  |  |
| PCIE_TX_CAP_N50 |  | 6707.13 |  | PCIE_TX_N50 | 505.21 |  | 7212.34 |  |  | PE_TX3_DR2_N | 9627.23 |  | 16839.57 |  | S23 | S23 | D85_PCIE_B_TX0_P | 505.9 |  | 17345.47 |  |  |  |  |  |  |  |  |  |  |  |
| PCIE_TX_CAP_P50 |  | 6706.84 | yes; within 1 mils | PCIE_TX_P50 | 505.2 | yes; within 1 mils | 7212.04 | yes; within 1 mils |  | PE_TX3_DR2_P | 9627.23 | yes; within 1 mils | 16839.27 | yes; within 5 mils | S24 | S24 | D85_PCIE_B_TX0_N | 505.9 | yes; within 1 mils | 17345.170000000002 | yes; within 5 mils |  |  |  |  |  |  |  |  |  |  |
| PCIE_TX_CAP_N51 |  | 6698.32 |  | PCIE_TX_N51 | 505.21 |  | 7203.53 |  |  | PE_TX4_DR2_N | 9698.26 |  | 16901.79 |  | E17 | E17 | D85_PCIE_B_TX1_P | 536.89 |  | 17438.68 |  |  |  |  |  |  |  |  |  |  |  |
| PCIE_TX_CAP_P51 |  | 6698.57 | yes; within 1 mils | PCIE_TX_P51 | 505.21 | yes; within 1 mils | 7203.78 | yes; within 1 mils |  | PE_TX4_DR2_P | 9698.23 | yes; within 1 mils | 16902.009999999998 | yes; within 5 mils | E18 | E18 | D85_PCIE_B_TX1_N | 536.82000000000005 | yes; within 1 mils | 17438.829999999998 | yes; within 5 mils |  |  |  |  |  |  |  |  |  |  |
|  |  |  |  |  |  | routing bundle delta | 8.8100000000004002 |  |  | routing bundle delta | 71.030000000000655 | routing bundle delta | 62.739999999997963 | yes; within 600mil |  |  | routing bundle delta | 30.990000000000009 | routing bundle delta | 93.659999999996217 |  |  |  |  |  |  |  |  |  |  |  |
|  |  |  |  |  |  | diff pair to pair delta | 54.949999999999818 | yes; within 2000mil |  | diff pair to pair delta | 228.76000000000022 | yes; within 2000mil | 262.28999999999724 | yes; within 2000mil |  |  | diff pair to pair delta | 724.67 | yes; within 2000mil | 588.69999999999709 | yes; within 2000mil |  |  |  |  |  |  |  |  |  |  |
| PM8536 to GF of PEB |  |  |  | Card Edge Connector | Connector of PDPB to U.2 Connector (J2) |  |  |  |  | SFF-8639 Conn | SFF-8639 Conn | M.2 Conn |  |  |  |  |  |  |  |  |  |  |  |  |  |  |  |  |  |  |  |
| Net Name | PKG Lengths | PCB Net Length | Differential Match | The Length of Connector | Net Name | PCB Net Length | Differential Match | Total Length | Differential Match | Pin of Connector | Pin of Connector | Net Name | PCB Net Length | Differential Match | Total Length | Differential Match |  |  |  |  |  |  |  |  |  |  |  |  |  |  |  |
| PCIE_RX_N48 |  | 7320.03 |  |  | PE_RX1_DR2_N | 9545.4699999999993 |  | 16865.5 |  | E13 | E13 | D85_PCIE_A_RX0_N | 1244.06 |  | 18109.560000000001 |  |  |  |  |  |  |  |  |  |  |  |  |  |  |  |  |
| PCIE_RX_P48 |  | 7320.07 | yes; within 1 mils |  | PE_RX1_DR2_P | 9545.43 | yes; within 1 mils | 16865.5 | yes; within 5 mils | E14 | E14 | D85_PCIE_A_RX0_P | 1244.6500000000001 | yes; within 1 mils | 18110.150000000001 | yes; within 5 mils |  |  |  |  |  |  |  |  |  |  |  |  |  |  |  |
| PCIE_RX_N49 |  | 7327.89 |  |  | PE_RX2_DR2_N | 9618.1200000000008 |  | 16946.010000000002 |  | S20 | S20 | D85_PCIE_A_RX1_N | 1537.67 |  | 18483.68 |  |  |  |  |  |  |  |  |  |  |  |  |  |  |  |  |
| PCIE_RX_P49 |  | 7328.51 | yes; within 1 mils |  | PE_RX2_DR2_P | 9618.0300000000007 | yes; within 1 mils | 16946.54 | yes; within 5 mils | S21 | S21 | D85_PCIE_A_RX1_P | 1538.32 | yes; within 1 mils | 18484.86 | yes; within 5 mils |  |  |  |  |  |  |  |  |  |  |  |  |  |  |  |
|  | routing bundle delta | 8.4800000000004729 |  |  | routing bundle delta | 72.690000000000509 | routing bundle delta | 81.040000000000873 | yes; within 600mil |  |  | routing bundle delta | 294.26 | routing bundle delta | 375.29999999999927 |  |  |  |  |  |  |  |  |  |  |  |  |  |  |  |  |
| PCIE_RX_N50 |  | 7367.08 |  |  | PE_RX3_DR2_N | 9702.44 |  | 17069.52 |  | S26 | S26 | D85_PCIE_B_RX0_N | 946.63 |  | 18016.150000000001 |  |  |  |  |  |  |  |  |  |  |  |  |  |  |  |  |
| PCIE_RX_P50 |  | 7367.6 | yes; within 1 mils |  | PE_RX3_DR2_P | 9702.3799999999992 | yes; within 1 mils | 17069.98 | yes; within 5 mils | S27 | S27 | D85_PCIE_B_RX0_P | 947.24 | yes; within 1 mils | 18017.22 | yes; within 5 mils |  |  |  |  |  |  |  |  |  |  |  |  |  |  |  |
| PCIE_RX_N51 |  | 7359.25 |  |  | PE_RX4_DR2_N | 9760.4599999999991 |  | 17119.71 |  | E20 | E20 | D85_PCIE_B_RX1_N | 955.34 |  | 18075.05 |  |  |  |  |  |  |  |  |  |  |  |  |  |  |  |  |
| PCIE_RX_P51 |  | 7359.47 | yes; within 1 mils |  | PE_RX4_DR2_P | 9760.4 | yes; within 1 mils | 17119.87 | yes; within 5 mils | E21 | E21 | D85_PCIE_B_RX1_P | 955.96 | yes; within 1 mils | 18075.829999999998 | yes; within 5 mils |  |  |  |  |  |  |  |  |  |  |  |  |  |  |  |
|  | routing bundle delta | 8.3500000000003638 |  |  | routing bundle delta | 58.079999999999927 | routing bundle delta | 50.349999999998545 | yes; within 600mil |  |  | routing bundle delta | 9.3300000000000409 | routing bundle delta | 59.679999999996653 |  |  |  |  |  |  |  |  |  |  |  |  |  |  |  |  |
|  | diff pair to pair delta | 47.570000000000618 | yes; within 2000mil |  | diff pair to pair delta | 215.02999999999884 | yes; within 2000mil | 254.36999999999898 | yes; within 2000mil |  |  | diff pair to pair delta | 591.68999999999994 | yes; within 2000mil | 468.70999999999913 | yes; within 2000mil |  |  |  |  |  |  |  |  |  |  |  |  |  |  |  |
| PM8536 to SSD7 |  |  |  |  |  |  |  |  |  |  |  |  |  |  | PCISLT68-14-GP-U | SKT-SAS28-P15-PCIE25-2-GP |  |  |  |  |  |  |  |  |  |  |  |  |  |  |  |
| PM8536 to GF of PEB |  |  |  |  |  |  |  |  | Card Edge Connector | Connector of PDPB to U.2 Connector (J7) |  |  |  |  | SFF-8639 Conn | SFF-8639 Conn | M.2 Conn |  |  |  |  |  |  |  |  |  |  |  |  |  |  |
| Net Name | PKG Lengths | PCB Net Length | Differential Match | Net Name | PCB Net Length | Differential Match | PEB Total Length | Differential Match | The Length of Connector | Net Name | PCB Net Length | Differential Match | Total Length | Differential Match | Pin of Connector | Pin of Connector | Net Name | PCB Net Length | Differential Match | Total Length | Differential Match |  |  |  |  |  |  |  |  |  |  |
| PCIE_TX_CAP_N44 |  | 6457.41 |  | PCIE_TX_N44 | 505.21 |  | 6962.62 |  |  | PE_TX1_DR7_N | 2443.6 |  | 9406.2199999999993 |  | E10 | E10 | D85_PCIE_A_TX0_P | 1053.4100000000001 |  | 10459.629999999999 |  |  |  |  |  |  |  |  |  |  |  |
| PCIE_TX_CAP_P44 |  | 6456.93 | yes; within 1 mils | PCIE_TX_P44 | 505.21 | yes; within 1 mils | 6962.14 | yes; within 1 mils |  | PE_TX1_DR7_P | 2443.6 | yes; within 1 mils | 9405.74 | yes; within 5 mils | E11 | E11 | D85_PCIE_A_TX0_N | 1053.3499999999999 | yes; within 1 mils | 10459.09 | yes; within 5 mils |  |  |  |  |  |  |  |  |  |  |
| PCIE_TX_CAP_N45 |  | 6515.95 |  | PCIE_TX_N45 | 505.21 |  | 7021.16 |  |  | PE_TX2_DR7_N | 2072.41 |  | 9093.57 |  | S17 | S17 | D85_PCIE_A_TX1_P | 1230.57 |  | 10324.14 |  |  |  |  |  |  |  |  |  |  |  |
| PCIE_TX_CAP_P45 |  | 6515.2 | yes; within 1 mils | PCIE_TX_P45 | 505.2 | yes; within 1 mils | 7020.4 | yes; within 1 mils |  | PE_TX2_DR7_P | 2072.4299999999998 | yes; within 1 mils | 9092.83 | yes; within 5 mils | S18 | S18 | D85_PCIE_A_TX1_N | 1230.52 | yes; within 1 mils | 10323.35 | yes; within 5 mils |  |  |  |  |  |  |  |  |  |  |
|  |  |  |  |  |  | routing bundle delta | 59.019999999999527 |  |  | routing bundle delta | 371.19000000000005 | routing bundle delta | 313.38999999999942 | yes; within 600mil |  |  | routing bundle delta | 177.22000000000003 | routing bundle delta | 136.27999999999884 |  |  |  |  |  |  |  |  |  |  |  |
| PCIE_TX_CAP_N46 |  | 6504.05 |  | PCIE_TX_N46 | 505.21 |  | 7009.26 |  |  | PE_TX3_DR7_N | 2041.73 |  | 9050.99 |  | S23 | S23 | D85_PCIE_B_TX0_P | 505.9 |  | 9556.89 |  |  |  |  |  |  |  |  |  |  |  |
| PCIE_TX_CAP_P46 |  | 6503.79 | yes; within 1 mils | PCIE_TX_P46 | 505.21 | yes; within 1 mils | 7009 | yes; within 1 mils |  | PE_TX3_DR7_P | 2041.74 | yes; within 1 mils | 9050.74 | yes; within 5 mils | S24 | S24 | D85_PCIE_B_TX0_N | 505.9 | yes; within 1 mils | 9556.64 | yes; within 5 mils |  |  |  |  |  |  |  |  |  |  |
| PCIE_TX_CAP_N47 |  | 6581.84 |  | PCIE_TX_N47 | 505.21 |  | 7087.05 |  |  | PE_TX4_DR7_N | 1995.57 |  | 9082.6200000000008 |  | E17 | E17 | D85_PCIE_B_TX1_P | 536.89 |  | 9619.51 |  |  |  |  |  |  |  |  |  |  |  |
| PCIE_TX_CAP_P47 |  | 6581.28 | yes; within 1 mils | PCIE_TX_P47 | 505.2 | yes; within 1 mils | 7086.48 | yes; within 1 mils |  | PE_TX4_DR7_P | 1995.57 | yes; within 1 mils | 9082.0499999999993 | yes; within 5 mils | E18 | E18 | D85_PCIE_B_TX1_N | 536.82000000000005 | yes; within 1 mils | 9618.869999999999 | yes; within 5 mils |  |  |  |  |  |  |  |  |  |  |
|  |  |  |  |  |  | routing bundle delta | 78.050000000000182 |  |  | routing bundle delta | 46.170000000000073 | routing bundle delta | 31.880000000001019 | yes; within 600mil |  |  | routing bundle delta | 30.990000000000009 | routing bundle delta | 62.8700000000008 |  |  |  |  |  |  |  |  |  |  |  |
|  |  |  |  |  |  | diff pair to pair delta | 124.90999999999985 | yes; within 2000mil |  | diff pair to pair delta | 448.03 | yes; within 2000mil | 355.47999999999956 | yes; within 2000mil |  |  | diff pair to pair delta | 724.67 | yes; within 2000mil | 902.98999999999978 | yes; within 2000mil |  |  |  |  |  |  |  |  |  |  |
| PM8536 to GF of PEB |  |  |  | Card Edge Connector | Connector of PDPB to U.2 Connector (J7) |  |  |  |  | SFF-8639 Conn | SFF-8639 Conn | M.2 Conn |  |  |  |  |  |  |  |  |  |  |  |  |  |  |  |  |  |  |  |
| Net Name | PKG Lengths | PCB Net Length | Differential Match | The Length of Connector | Net Name | PCB Net Length | Differential Match | Total Length | Differential Match | Pin of Connector | Pin of Connector | Net Name | PCB Net Length | Differential Match | Total Length | Differential Match |  |  |  |  |  |  |  |  |  |  |  |  |  |  |  |
| PCIE_RX_N44 |  | 7058.08 |  |  | PE_RX1_DR7_N | 2396.08 |  | 9454.16 |  | E13 | E13 | D85_PCIE_A_RX0_N | 1244.06 |  | 10698.22 |  |  |  |  |  |  |  |  |  |  |  |  |  |  |  |  |
| PCIE_RX_P44 |  | 7058.21 | yes; within 1 mils |  | PE_RX1_DR7_P | 2396.08 | yes; within 1 mils | 9454.2900000000009 | yes; within 5 mils | E14 | E14 | D85_PCIE_A_RX0_P | 1244.6500000000001 | yes; within 1 mils | 10698.94 | yes; within 5 mils |  |  |  |  |  |  |  |  |  |  |  |  |  |  |  |
| PCIE_RX_N45 |  | 7135.15 |  |  | PE_RX2_DR7_N | 2068.34 |  | 9203.49 |  | S20 | S20 | D85_PCIE_A_RX1_N | 1537.67 |  | 10741.16 |  |  |  |  |  |  |  |  |  |  |  |  |  |  |  |  |
| PCIE_RX_P45 |  | 7135.01 | yes; within 1 mils |  | PE_RX2_DR7_P | 2068.3200000000002 | yes; within 1 mils | 9203.33 | yes; within 5 mils | S21 | S21 | D85_PCIE_A_RX1_P | 1538.32 | yes; within 1 mils | 10741.65 | yes; within 5 mils |  |  |  |  |  |  |  |  |  |  |  |  |  |  |  |
|  | routing bundle delta | 77.069999999999709 |  |  | routing bundle delta | 327.75999999999976 | routing bundle delta | 250.96000000000095 | yes; within 600mil |  |  | routing bundle delta | 294.26 | routing bundle delta | 43.430000000000291 |  |  |  |  |  |  |  |  |  |  |  |  |  |  |  |  |
| PCIE_RX_N46 |  | 7117.78 |  |  | PE_RX3_DR7_N | 2013.83 |  | 9131.61 |  | S26 | S26 | D85_PCIE_B_RX0_N | 946.63 |  | 10078.24 |  |  |  |  |  |  |  |  |  |  |  |  |  |  |  |  |
| PCIE_RX_P46 |  | 7117.68 | yes; within 1 mils |  | PE_RX3_DR7_P | 2013.8 | yes; within 1 mils | 9131.48 | yes; within 5 mils | S27 | S27 | D85_PCIE_B_RX0_P | 947.24 | yes; within 1 mils | 10078.719999999999 | yes; within 5 mils |  |  |  |  |  |  |  |  |  |  |  |  |  |  |  |
| PCIE_RX_N47 |  | 7434.27 |  |  | PE_RX4_DR7_N | 2166.6799999999998 |  | 9600.9500000000007 |  | E20 | E20 | D85_PCIE_B_RX1_N | 955.34 |  | 10556.29 |  |  |  |  |  |  |  |  |  |  |  |  |  |  |  |  |
| PCIE_RX_P47 |  | 7433.95 | yes; within 1 mils |  | PE_RX4_DR7_P | 2166.69 | yes; within 1 mils | 9600.64 | yes; within 5 mils | E21 | E21 | D85_PCIE_B_RX1_P | 955.96 | yes; within 1 mils | 10556.599999999999 | yes; within 5 mils |  |  |  |  |  |  |  |  |  |  |  |  |  |  |  |
|  | routing bundle delta | 316.59000000000015 |  |  | routing bundle delta | 152.8900000000001 | routing bundle delta | 469.47000000000116 | yes; within 600mil |  |  | routing bundle delta | 9.3300000000000409 | routing bundle delta | 478.35999999999876 |  |  |  |  |  |  |  |  |  |  |  |  |  |  |  |  |
|  | diff pair to pair delta | 376.19000000000051 | yes; within 2000mil |  | diff pair to pair delta | 382.28 | yes; within 2000mil | 469.47000000000116 | yes; within 2000mil |  |  | diff pair to pair delta | 591.68999999999994 | yes; within 2000mil | 663.40999999999985 | yes; within 2000mil |  |  |  |  |  |  |  |  |  |  |  |  |  |  |  |
| PM8536 to SSD3 |  |  |  |  |  |  |  |  |  |  |  |  |  |  | PCISLT68-14-GP-U | SKT-SAS28-P15-PCIE25-2-GP |  |  |  |  |  |  |  |  |  |  |  |  |  |  |  |
| PM8536 to GF of PEB |  |  |  |  |  |  |  |  | Card Edge Connector | Connector of PDPB to U.2 Connector (J3) |  |  |  |  | SFF-8639 Conn | SFF-8639 Conn | M.2 Conn |  |  |  |  |  |  |  |  |  |  |  |  |  |  |
| Net Name | PKG Lengths | PCB Net Length | Differential Match | Net Name | PCB Net Length | Differential Match | PEB Total Length | Differential Match | The Length of Connector | Net Name | PCB Net Length | Differential Match | Total Length | Differential Match | Pin of Connector | Pin of Connector | Net Name | PCB Net Length | Differential Match | Total Length | Differential Match |  |  |  |  |  |  |  |  |  |  |
| PCIE_TX_CAP_N40 |  | 6370.8 |  | PCIE_TX_N40 | 505.21 |  | 6876.01 |  |  | PE_TX1_DR3_N | 11068.14 |  | 17944.150000000001 |  | E10 | E10 | D85_PCIE_A_TX0_P | 1053.4100000000001 |  | 18997.560000000001 |  |  |  |  |  |  |  |  |  |  |  |
| PCIE_TX_CAP_P40 |  | 6370.77 | yes; within 1 mils | PCIE_TX_P40 | 505.21 | yes; within 1 mils | 6875.9800000000005 | yes; within 1 mils |  | PE_TX1_DR3_P | 11068.01 | yes; within 1 mils | 17943.990000000002 | yes; within 5 mils | E11 | E11 | D85_PCIE_A_TX0_N | 1053.3499999999999 | yes; within 1 mils | 18997.34 | yes; within 5 mils |  |  |  |  |  |  |  |  |  |  |
| PCIE_TX_CAP_N41 |  | 6423.64 |  | PCIE_TX_N41 | 505.21 |  | 6928.85 |  |  | PE_TX2_DR3_N | 11051.2 |  | 17980.050000000003 |  | S17 | S17 | D85_PCIE_A_TX1_P | 1230.57 |  | 19210.620000000003 |  |  |  |  |  |  |  |  |  |  |  |
| PCIE_TX_CAP_P41 |  | 6423.3 | yes; within 1 mils | PCIE_TX_P41 | 505.21 | yes; within 1 mils | 6928.51 | yes; within 1 mils |  | PE_TX2_DR3_P | 11051.22 | yes; within 1 mils | 17979.73 | yes; within 5 mils | S18 | S18 | D85_PCIE_A_TX1_N | 1230.52 | yes; within 1 mils | 19210.25 | yes; within 5 mils |  |  |  |  |  |  |  |  |  |  |
|  |  |  |  |  |  | routing bundle delta | 52.869999999999891 |  |  | routing bundle delta | 16.93999999999869 |  | 36.06000000000131 | yes; within 600mil |  |  | routing bundle delta | 177.22000000000003 | routing bundle delta | 213.28000000000247 |  |  |  |  |  |  |  |  |  |  |  |
| PCIE_TX_CAP_N42 |  | 6409.96 |  | PCIE_TX_N42 | 505.21 |  | 6915.17 |  |  | PE_TX3_DR3_N | 11070.82 |  | 17985.989999999998 |  | S23 | S23 | D85_PCIE_B_TX0_P | 505.9 |  | 18491.89 |  |  |  |  |  |  |  |  |  |  |  |
| PCIE_TX_CAP_P42 |  | 6410.1 | yes; within 1 mils | PCIE_TX_P42 | 505.2 | yes; within 1 mils | 6915.3 | yes; within 1 mils |  | PE_TX3_DR3_P | 11070.89 | yes; within 1 mils | 17986.189999999999 | yes; within 5 mils | S24 | S24 | D85_PCIE_B_TX0_N | 505.9 | yes; within 1 mils | 18492.09 | yes; within 5 mils |  |  |  |  |  |  |  |  |  |  |
| PCIE_TX_CAP_N43 |  | 6468.14 |  | PCIE_TX_N43 | 505.21 |  | 6973.35 |  |  | PE_TX4_DR3_N | 11080.07 |  | 18053.419999999998 |  | E17 | E17 | D85_PCIE_B_TX1_P | 536.89 |  | 18590.309999999998 |  |  |  |  |  |  |  |  |  |  |  |
| PCIE_TX_CAP_P43 |  | 6468.01 | yes; within 1 mils | PCIE_TX_P43 | 505.21 | yes; within 1 mils | 6973.22 | yes; within 1 mils |  | PE_TX4_DR3_P | 11080.03 | yes; within 1 mils | 18053.25 | yes; within 5 mils | E18 | E18 | D85_PCIE_B_TX1_N | 536.82000000000005 | yes; within 1 mils | 18590.07 | yes; within 5 mils |  |  |  |  |  |  |  |  |  |  |
|  |  |  |  |  |  | routing bundle delta | 58.180000000000291 |  |  | routing bundle delta | 9.25 |  | 67.430000000000291 | yes; within 600mil |  |  | routing bundle delta | 30.990000000000009 | routing bundle delta | 98.419999999998254 |  |  |  |  |  |  |  |  |  |  |  |
|  |  |  |  |  |  | diff pair to pair delta | 97.369999999999891 | yes; within 2000mil |  | diff pair to pair delta | 28.869999999998981 | yes; within 2000mil | 109.42999999999665 | yes; within 2000mil |  |  | diff pair to pair delta | 724.67 | yes; within 2000mil | 718.7300000000032 | yes; within 2000mil |  |  |  |  |  |  |  |  |  |  |
| PM8536 to GF of PEB |  |  |  | Card Edge Connector | Connector of PDPB to U.2 Connector (J3) |  |  |  |  | SFF-8639 Conn | SFF-8639 Conn | M.2 Conn |  |  |  |  |  |  |  |  |  |  |  |  |  |  |  |  |  |  |  |
| Net Name | PKG Lengths | PCB Net Length | Differential Match | The Length of Connector | Net Name | PCB Net Length | Differential Match | Total Length | Differential Match | Pin of Connector | Pin of Connector | Net Name | PCB Net Length | Differential Match | Total Length | Differential Match |  |  |  |  |  |  |  |  |  |  |  |  |  |  |  |
| PCIE_RX_N40 |  | 7000.02 |  |  | PE_RX1_DR3_N | 11078.47 |  | 18078.489999999998 |  | E13 | E13 | D85_PCIE_A_RX0_N | 1244.06 |  | 19322.55 |  |  |  |  |  |  |  |  |  |  |  |  |  |  |  |  |
| PCIE_RX_P40 |  | 6999.66 | yes; within 1 mils |  | PE_RX1_DR3_P | 11078.3 | yes; within 1 mils | 18077.96 | yes; within 5 mils | E14 | E14 | D85_PCIE_A_RX0_P | 1244.6500000000001 | yes; within 1 mils | 19322.61 | yes; within 5 mils |  |  |  |  |  |  |  |  |  |  |  |  |  |  |  |
| PCIE_RX_N41 |  | 7098.29 |  |  | PE_RX2_DR3_N | 11056.54 |  | 18154.830000000002 |  | S20 | S20 | D85_PCIE_A_RX1_N | 1537.67 |  | 19692.5 |  |  |  |  |  |  |  |  |  |  |  |  |  |  |  |  |
| PCIE_RX_P41 |  | 7098.7 | yes; within 1 mils |  | PE_RX2_DR3_P | 11056.53 | yes; within 1 mils | 18155.23 | yes; within 5 mils | S21 | S21 | D85_PCIE_A_RX1_P | 1538.32 | yes; within 1 mils | 19693.55 | yes; within 5 mils |  |  |  |  |  |  |  |  |  |  |  |  |  |  |  |
|  | routing bundle delta | 99.039999999999964 |  |  | routing bundle delta | 21.93999999999869 |  | 77.270000000000437 | yes; within 600mil |  |  | routing bundle delta | 294.26 | routing bundle delta | 371 |  |  |  |  |  |  |  |  |  |  |  |  |  |  |  |  |
| PCIE_RX_N42 |  | 7074.72 |  |  | PE_RX3_DR3_N | 11107.93 |  | 18182.650000000001 |  | S26 | S26 | D85_PCIE_B_RX0_N | 946.63 |  | 19129.280000000002 |  |  |  |  |  |  |  |  |  |  |  |  |  |  |  |  |
| PCIE_RX_P42 |  | 7074.89 | yes; within 1 mils |  | PE_RX3_DR3_P | 11107.92 | yes; within 1 mils | 18182.810000000001 | yes; within 5 mils | S27 | S27 | D85_PCIE_B_RX0_P | 947.24 | yes; within 1 mils | 19130.050000000003 | yes; within 5 mils |  |  |  |  |  |  |  |  |  |  |  |  |  |  |  |
| PCIE_RX_N43 |  | 7104.56 |  |  | PE_RX4_DR3_N | 11132.52 |  | 18237.080000000002 |  | E20 | E20 | D85_PCIE_B_RX1_N | 955.34 |  | 19192.420000000002 |  |  |  |  |  |  |  |  |  |  |  |  |  |  |  |  |
| PCIE_RX_P43 |  | 7104.29 | yes; within 1 mils |  | PE_RX4_DR3_P | 11132.46 | yes; within 1 mils | 18236.75 | yes; within 5 mils | E21 | E21 | D85_PCIE_B_RX1_P | 955.96 | yes; within 1 mils | 19192.71 | yes; within 5 mils |  |  |  |  |  |  |  |  |  |  |  |  |  |  |  |
|  | routing bundle delta | 29.840000000000146 |  |  | routing bundle delta | 24.600000000000364 |  | 54.430000000000291 | yes; within 600mil |  |  | routing bundle delta | 9.3300000000000409 | routing bundle delta | 63.429999999996653 |  |  |  |  |  |  |  |  |  |  |  |  |  |  |  |  |
|  | diff pair to pair delta | 104.90000000000055 | yes; within 2000mil |  | diff pair to pair delta | 75.989999999999782 | yes; within 2000mil | 159.12000000000262 | yes; within 2000mil |  |  | diff pair to pair delta | 591.68999999999994 | yes; within 2000mil | 564.2699999999968 | yes; within 2000mil |  |  |  |  |  |  |  |  |  |  |  |  |  |  |  |
| PM8536 to SSD4 |  |  |  |  |  |  |  |  |  |  |  |  |  |  | PCISLT68-14-GP-U | SKT-SAS28-P15-PCIE25-2-GP |  |  |  |  |  |  |  |  |  |  |  |  |  |  |  |
| PM8536 to GF of PEB |  |  |  |  |  |  |  |  | Card Edge Connector | Connector of PDPB to U.2 Connector (J4) |  |  |  |  | SFF-8639 Conn | SFF-8639 Conn | M.2 Conn |  |  |  |  |  |  |  |  |  |  |  |  |  |  |
| Net Name | PKG Lengths | PCB Net Length | Differential Match | Net Name | PCB Net Length | Differential Match | PEB Total Length | Differential Match | The Length of Connector | Net Name | PCB Net Length | Differential Match | Total Length | Differential Match | Pin of Connector | Pin of Connector | Net Name | PCB Net Length | Differential Match | Total Length | Differential Match |  |  |  |  |  |  |  |  |  |  |
| PCIE_TX_CAP_N36 |  | 5905.01 |  | PCIE_TX_N36 | 505.21 |  | 6410.22 |  |  | PE_TX1_DR4_N | 12696.71 |  | 19106.93 |  | E10 | E10 | D85_PCIE_A_TX0_P | 1053.4100000000001 |  | 20160.34 |  |  |  |  |  |  |  |  |  |  |  |
| PCIE_TX_CAP_P36 |  | 5904.38 | yes; within 1 mils | PCIE_TX_P36 | 505.21 | yes; within 1 mils | 6409.59 | yes; within 1 mils |  | PE_TX1_DR4_P | 12696.61 | yes; within 1 mils | 19106.2 | yes; within 5 mils | E11 | E11 | D85_PCIE_A_TX0_N | 1053.3499999999999 | yes; within 1 mils | 20159.55 | yes; within 5 mils |  |  |  |  |  |  |  |  |  |  |
| PCIE_TX_CAP_N37 |  | 5949.51 |  | PCIE_TX_N37 | 505.21 |  | 6454.72 |  |  | PE_TX2_DR4_N | 12696.17 |  | 19150.89 |  | S17 | S17 | D85_PCIE_A_TX1_P | 1230.57 |  | 20381.46 |  |  |  |  |  |  |  |  |  |  |  |
| PCIE_TX_CAP_P37 |  | 5949.78 | yes; within 1 mils | PCIE_TX_P37 | 505.21 | yes; within 1 mils | 6454.99 | yes; within 1 mils |  | PE_TX2_DR4_P | 12696.16 | yes; within 1 mils | 19151.150000000001 | yes; within 5 mils | S18 | S18 | D85_PCIE_A_TX1_N | 1230.52 | yes; within 1 mils | 20381.670000000002 | yes; within 5 mils |  |  |  |  |  |  |  |  |  |  |
|  |  |  |  |  |  | routing bundle delta | 45.399999999999636 |  |  | routing bundle delta | 0.5499999999992724 |  | 44.950000000000728 | yes; within 600mil |  |  | routing bundle delta | 177.22000000000003 | routing bundle delta | 222.12000000000262 |  |  |  |  |  |  |  |  |  |  |  |
| PCIE_TX_CAP_N38 |  | 6414.02 |  | PCIE_TX_N38 | 505.21 |  | 6919.2300000000005 |  |  | PE_TX3_DR4_N | 12489.01 |  | 19408.240000000002 |  | S23 | S23 | D85_PCIE_B_TX0_P | 505.9 |  | 19914.140000000003 |  |  |  |  |  |  |  |  |  |  |  |
| PCIE_TX_CAP_P38 |  | 6413.51 | yes; within 1 mils | PCIE_TX_P38 | 505.2 | yes; within 1 mils | 6918.71 | yes; within 1 mils |  | PE_TX3_DR4_P | 12488.12 | yes; within 1 mils | 19406.830000000002 | yes; within 5 mils | S24 | S24 | D85_PCIE_B_TX0_N | 505.9 | yes; within 1 mils | 19912.730000000003 | yes; within 5 mils |  |  |  |  |  |  |  |  |  |  |
| PCIE_TX_CAP_N39 |  | 6434.99 |  | PCIE_TX_N39 | 505.21 |  | 6940.2 |  |  | PE_TX4_DR4_N | 12493.92 |  | 19434.12 |  | E17 | E17 | D85_PCIE_B_TX1_P | 536.89 |  | 19971.009999999998 |  |  |  |  |  |  |  |  |  |  |  |
| PCIE_TX_CAP_P39 |  | 6434.46 | yes; within 1 mils | PCIE_TX_P39 | 505.21 | yes; within 1 mils | 6939.67 | yes; within 1 mils |  | PE_TX4_DR4_P | 12493.64 | yes; within 1 mils | 19433.309999999998 | yes; within 5 mils | E18 | E18 | D85_PCIE_B_TX1_N | 536.82000000000005 | yes; within 1 mils | 19970.129999999997 | yes; within 5 mils |  |  |  |  |  |  |  |  |  |  |
|  |  |  |  |  |  | routing bundle delta | 21.489999999999782 |  |  | routing bundle delta | 5.7999999999992724 |  | 27.289999999997235 | yes; within 600mil |  |  | routing bundle delta | 30.990000000000009 | routing bundle delta | 58.279999999995198 |  |  |  |  |  |  |  |  |  |  |  |
|  |  |  |  |  |  | diff pair to pair delta | 530.60999999999967 | yes; within 2000mil |  | diff pair to pair delta | 208.58999999999833 | yes; within 2000mil | 327.91999999999825 | yes; within 2000mil |  |  | diff pair to pair delta | 724.67 | yes; within 2000mil | 468.93999999999869 | yes; within 2000mil |  |  |  |  |  |  |  |  |  |  |
| PM8536 to GF of PEB |  |  |  | Card Edge Connector | Connector of PDPB to U.2 Connector (J4) |  |  |  |  | SFF-8639 Conn | SFF-8639 Conn | M.2 Conn |  |  |  |  |  |  |  |  |  |  |  |  |  |  |  |  |  |  |  |
| Net Name | PKG Lengths | PCB Net Length | Differential Match | The Length of Connector | Net Name | PCB Net Length | Differential Match | Total Length | Differential Match | Pin of Connector | Pin of Connector | Net Name | PCB Net Length | Differential Match | Total Length | Differential Match |  |  |  |  |  |  |  |  |  |  |  |  |  |  |  |
| PCIE_RX_N36 |  | 6652.69 |  |  | PE_RX1_DR4_N | 12577.79 |  | 19230.48 |  | E13 | E13 | D85_PCIE_A_RX0_N | 1244.06 |  | 20474.54 |  |  |  |  |  |  |  |  |  |  |  |  |  |  |  |  |
| PCIE_RX_P36 |  | 6651.97 | yes; within 1 mils |  | PE_RX1_DR4_P | 12577.82 | yes; within 1 mils | 19229.79 | yes; within 5 mils | E14 | E14 | D85_PCIE_A_RX0_P | 1244.6500000000001 | yes; within 1 mils | 20474.440000000002 | yes; within 5 mils |  |  |  |  |  |  |  |  |  |  |  |  |  |  |  |
| PCIE_RX_N37 |  | 6659.47 |  |  | PE_RX2_DR4_N | 12587.98 |  | 19247.45 |  | S20 | S20 | D85_PCIE_A_RX1_N | 1537.67 |  | 20785.120000000003 |  |  |  |  |  |  |  |  |  |  |  |  |  |  |  |  |
| PCIE_RX_P37 |  | 6658.88 | yes; within 1 mils |  | PE_RX2_DR4_P | 12587.92 | yes; within 1 mils | 19246.8 | yes; within 5 mils | S21 | S21 | D85_PCIE_A_RX1_P | 1538.32 | yes; within 1 mils | 20785.12 | yes; within 5 mils |  |  |  |  |  |  |  |  |  |  |  |  |  |  |  |
|  | routing bundle delta | 7.5 |  |  | routing bundle delta | 10.18999999999869 |  | 17.659999999999854 | yes; within 600mil |  |  | routing bundle delta | 294.26 | routing bundle delta | 310.68000000000029 |  |  |  |  |  |  |  |  |  |  |  |  |  |  |  |  |
| PCIE_RX_N38 |  | 6968.17 |  |  | PE_RX3_DR4_N | 12497.44 |  | 19465.61 |  | S26 | S26 | D85_PCIE_B_RX0_N | 946.63 |  | 20412.240000000002 |  |  |  |  |  |  |  |  |  |  |  |  |  |  |  |  |
| PCIE_RX_P38 |  | 6968.17 | yes; within 1 mils |  | PE_RX3_DR4_P | 12497.42 | yes; within 1 mils | 19465.59 | yes; within 5 mils | S27 | S27 | D85_PCIE_B_RX0_P | 947.24 | yes; within 1 mils | 20412.830000000002 | yes; within 5 mils |  |  |  |  |  |  |  |  |  |  |  |  |  |  |  |
| PCIE_RX_N39 |  | 6996.77 |  |  | PE_RX4_DR4_N | 12502.67 |  | 19499.440000000002 |  | E20 | E20 | D85_PCIE_B_RX1_N | 955.34 |  | 20454.780000000002 |  |  |  |  |  |  |  |  |  |  |  |  |  |  |  |  |
| PCIE_RX_P39 |  | 6997.13 | yes; within 1 mils |  | PE_RX4_DR4_P | 12502.65 | yes; within 1 mils | 19499.78 | yes; within 5 mils | E21 | E21 | D85_PCIE_B_RX1_P | 955.96 | yes; within 1 mils | 20455.739999999998 | yes; within 5 mils |  |  |  |  |  |  |  |  |  |  |  |  |  |  |  |
|  | routing bundle delta | 28.960000000000036 |  |  | routing bundle delta | 5.25 |  | 34.18999999999869 | yes; within 600mil |  |  | routing bundle delta | 9.3300000000000409 | routing bundle delta | 43.499999999996362 |  |  |  |  |  |  |  |  |  |  |  |  |  |  |  |  |
|  | diff pair to pair delta | 345.15999999999985 | yes; within 2000mil |  | diff pair to pair delta | 90.559999999999491 | yes; within 2000mil | 269.98999999999796 | yes; within 2000mil |  |  | diff pair to pair delta | 591.68999999999994 | yes; within 2000mil | 372.88000000000102 | yes; within 2000mil |  |  |  |  |  |  |  |  |  |  |  |  |  |  |  |
| PM8536 to SSD12 |  |  |  |  |  |  |  |  |  |  |  |  |  |  | PCISLT68-14-GP-U | SKT-SAS28-P15-PCIE25-2-GP |  |  |  |  |  |  |  |  |  |  |  |  |  |  |  |
| PM8536 to GF of PEB |  |  |  |  |  |  |  |  | Card Edge Connector | Connector of PDPB to U.2 Connector (J12) |  |  |  |  | SFF-8639 Conn | SFF-8639 Conn | M.2 Conn |  |  |  |  |  |  |  |  |  |  |  |  |  |  |
| Net Name | PKG Lengths | PCB Net Length | Differential Match | Net Name | PCB Net Length | Differential Match | PEB Total Length | Differential Match | The Length of Connector | Net Name | PCB Net Length | Differential Match | Total Length | Differential Match | Pin of Connector | Pin of Connector | Net Name | PCB Net Length | Differential Match | Total Length | Differential Match |  |  |  |  |  |  |  |  |  |  |
| PCIE_TX_CAP_N32 |  | 5997.92 |  | PCIE_TX_N32 | 505.21 |  | 6503.13 |  |  | PE_TX1_DR12_N | 4091.77 |  | 10594.9 |  | E10 | E10 | D85_PCIE_A_TX0_P | 1053.4100000000001 |  | 11648.31 |  |  |  |  |  |  |  |  |  |  |  |
| PCIE_TX_CAP_P32 |  | 5997.29 | yes; within 1 mils | PCIE_TX_P32 | 505.21 | yes; within 1 mils | 6502.5 | yes; within 1 mils |  | PE_TX1_DR12_P | 4091.73 | yes; within 1 mils | 10594.23 | yes; within 5 mils | E11 | E11 | D85_PCIE_A_TX0_N | 1053.3499999999999 | yes; within 1 mils | 11647.58 | yes; within 5 mils |  |  |  |  |  |  |  |  |  |  |
| PCIE_TX_CAP_N33 |  | 6027.4 |  | PCIE_TX_N33 | 505.21 |  | 6532.61 |  |  | PE_TX2_DR12_N | 3622.09 |  | 10154.700000000001 |  | S17 | S17 | D85_PCIE_A_TX1_P | 1230.57 |  | 11385.27 |  |  |  |  |  |  |  |  |  |  |  |
| PCIE_TX_CAP_P33 |  | 6027.29 | yes; within 1 mils | PCIE_TX_P33 | 505.2 | yes; within 1 mils | 6532.49 | yes; within 1 mils |  | PE_TX2_DR12_P | 3621.9 | yes; within 1 mils | 10154.39 | yes; within 5 mils | S18 | S18 | D85_PCIE_A_TX1_N | 1230.52 | yes; within 1 mils | 11384.91 | yes; within 5 mils |  |  |  |  |  |  |  |  |  |  |
|  |  |  |  |  |  | routing bundle delta | 30.109999999999673 |  |  | routing bundle delta | 469.86999999999989 | routing bundle delta | 440.51000000000022 | yes; within 600mil |  |  | routing bundle delta | 177.22000000000003 | routing bundle delta | 263.39999999999964 |  |  |  |  |  |  |  |  |  |  |  |
| PCIE_TX_CAP_N34 |  | 5946.02 |  | PCIE_TX_N34 | 505.21 |  | 6451.2300000000005 |  |  | PE_TX3_DR12_N | 3455.21 |  | 9906.44 |  | S23 | S23 | D85_PCIE_B_TX0_P | 505.9 |  | 10412.34 |  |  |  |  |  |  |  |  |  |  |  |
| PCIE_TX_CAP_P34 |  | 5945.54 | yes; within 1 mils | PCIE_TX_P34 | 505.21 | yes; within 1 mils | 6450.75 | yes; within 1 mils |  | PE_TX3_DR12_P | 3455.05 | yes; within 1 mils | 9905.7999999999993 | yes; within 5 mils | S24 | S24 | D85_PCIE_B_TX0_N | 505.9 | yes; within 1 mils | 10411.699999999999 | yes; within 5 mils |  |  |  |  |  |  |  |  |  |  |
| PCIE_TX_CAP_N35 |  | 5943.76 |  | PCIE_TX_N35 | 505.21 |  | 6448.97 |  |  | PE_TX4_DR12_N | 3297.63 |  | 9746.6 |  | E17 | E17 | D85_PCIE_B_TX1_P | 536.89 |  | 10283.49 |  |  |  |  |  |  |  |  |  |  |  |
| PCIE_TX_CAP_P35 |  | 5944.28 | yes; within 1 mils | PCIE_TX_P35 | 505.21 | yes; within 1 mils | 6449.49 | yes; within 1 mils |  | PE_TX4_DR12_P | 3297.16 | yes; within 1 mils | 9746.65 | yes; within 5 mils | E18 | E18 | D85_PCIE_B_TX1_N | 536.82000000000005 | yes; within 1 mils | 10283.469999999999 | yes; within 5 mils |  |  |  |  |  |  |  |  |  |  |
|  |  |  |  |  |  | routing bundle delta | 2.2600000000002183 |  |  | routing bundle delta | 158.05000000000018 | routing bundle delta | 159.84000000000015 | yes; within 600mil |  |  | routing bundle delta | 30.990000000000009 | routing bundle delta | 128.8700000000008 |  |  |  |  |  |  |  |  |  |  |  |
|  |  |  |  |  |  | diff pair to pair delta | 83.639999999999418 | yes; within 2000mil |  | diff pair to pair delta | 794.61000000000013 | yes; within 2000mil | 848.29999999999927 | yes; within 2000mil |  |  | diff pair to pair delta | 724.67 | yes; within 2000mil | 1364.8400000000001 | yes; within 2000mil |  |  |  |  |  |  |  |  |  |  |
| PM8536 to GF of PEB |  |  |  | Card Edge Connector | Connector of PDPB to U.2 Connector (J12) |  |  |  |  | SFF-8639 Conn | SFF-8639 Conn | M.2 Conn |  |  |  |  |  |  |  |  |  |  |  |  |  |  |  |  |  |  |  |
| Net Name | PKG Lengths | PCB Net Length | Differential Match | The Length of Connector | Net Name | PCB Net Length | Differential Match | Total Length | Differential Match | Pin of Connector | Pin of Connector | Net Name | PCB Net Length | Differential Match | Total Length | Differential Match |  |  |  |  |  |  |  |  |  |  |  |  |  |  |  |
| PCIE_RX_N32 |  | 6740.71 |  |  | PE_RX1_DR12_N | 3918.81 |  | 10659.52 |  | E13 | E13 | D85_PCIE_A_RX0_N | 1244.06 |  | 11903.58 |  |  |  |  |  |  |  |  |  |  |  |  |  |  |  |  |
| PCIE_RX_P32 |  | 6739.97 | yes; within 1 mils |  | PE_RX1_DR12_P | 3918.02 | yes; within 1 mils | 10657.99 | yes; within 5 mils | E14 | E14 | D85_PCIE_A_RX0_P | 1244.6500000000001 | yes; within 1 mils | 11902.64 | yes; within 5 mils |  |  |  |  |  |  |  |  |  |  |  |  |  |  |  |
| PCIE_RX_N33 |  | 6773.41 |  |  | PE_RX2_DR12_N | 3521.23 |  | 10294.64 |  | S20 | S20 | D85_PCIE_A_RX1_N | 1537.67 |  | 11832.31 |  |  |  |  |  |  |  |  |  |  |  |  |  |  |  |  |
| PCIE_RX_P33 |  | 6773.19 | yes; within 1 mils |  | PE_RX2_DR12_P | 3520.59 | yes; within 1 mils | 10293.779999999999 | yes; within 5 mils | S21 | S21 | D85_PCIE_A_RX1_P | 1538.32 | yes; within 1 mils | 11832.099999999999 | yes; within 5 mils |  |  |  |  |  |  |  |  |  |  |  |  |  |  |  |
|  | routing bundle delta | 33.4399999999996 |  |  | routing bundle delta | 398.2199999999998 | routing bundle delta | 365.7400000000016 | yes; within 600mil |  |  | routing bundle delta | 294.26 | routing bundle delta | 71.480000000001382 |  |  |  |  |  |  |  |  |  |  |  |  |  |  |  |  |
| PCIE_RX_N34 |  | 6726.49 |  |  | PE_RX3_DR12_N | 3381.96 |  | 10108.450000000001 |  | S26 | S26 | D85_PCIE_B_RX0_N | 946.63 |  | 11055.08 |  |  |  |  |  |  |  |  |  |  |  |  |  |  |  |  |
| PCIE_RX_P34 |  | 6725.96 | yes; within 1 mils |  | PE_RX3_DR12_P | 3381.2 | yes; within 1 mils | 10107.16 | yes; within 5 mils | S27 | S27 | D85_PCIE_B_RX0_P | 947.24 | yes; within 1 mils | 11054.4 | yes; within 5 mils |  |  |  |  |  |  |  |  |  |  |  |  |  |  |  |
| PCIE_RX_N35 |  | 6762.83 |  |  | PE_RX4_DR12_N | 3270.19 |  | 10033.02 |  | E20 | E20 | D85_PCIE_B_RX1_N | 955.34 |  | 10988.36 |  |  |  |  |  |  |  |  |  |  |  |  |  |  |  |  |
| PCIE_RX_P35 |  | 6762.53 | yes; within 1 mils |  | PE_RX4_DR12_P | 3269.95 | yes; within 1 mils | 10032.48 | yes; within 5 mils | E21 | E21 | D85_PCIE_B_RX1_P | 955.96 | yes; within 1 mils | 10988.439999999999 | yes; within 5 mils |  |  |  |  |  |  |  |  |  |  |  |  |  |  |  |
|  | routing bundle delta | 36.869999999999891 |  |  | routing bundle delta | 112.01000000000022 | routing bundle delta | 75.970000000001164 | yes; within 600mil |  |  | routing bundle delta | 9.3300000000000409 | routing bundle delta | 66.719999999999345 |  |  |  |  |  |  |  |  |  |  |  |  |  |  |  |  |
|  | diff pair to pair delta | 47.449999999999818 | yes; within 2000mil |  | diff pair to pair delta | 648.86000000000013 | yes; within 2000mil | 627.04000000000087 | yes; within 2000mil |  |  | diff pair to pair delta | 591.68999999999994 | yes; within 2000mil | 915.21999999999935 | yes; within 2000mil |  |  |  |  |  |  |  |  |  |  |  |  |  |  |  |
| PM8536 to SSD8 |  |  |  |  |  |  |  |  |  |  |  |  |  |  | PCISLT68-14-GP-U | SKT-SAS28-P15-PCIE25-2-GP |  |  |  |  |  |  |  |  |  |  |  |  |  |  |  |
| PM8536 to GF of PEB |  |  |  |  |  |  |  |  | Card Edge Connector | Connector of PDPB to U.2 Connector (J8) |  |  |  |  | SFF-8639 Conn | SFF-8639 Conn | M.2 Conn |  |  |  |  |  |  |  |  |  |  |  |  |  |  |
| Net Name | PKG Lengths | PCB Net Length | Differential Match | Net Name | PCB Net Length | Differential Match | PEB Total Length | Differential Match | The Length of Connector | Net Name | PCB Net Length | Differential Match | Total Length | Differential Match | Pin of Connector | Pin of Connector | Net Name | PCB Net Length | Differential Match | Total Length | Differential Match |  |  |  |  |  |  |  |  |  |  |
| PCIE_TX_CAP_N28 |  | 6540.9 |  | PCIE_TX_N28 | 505.21 |  | 7046.11 |  |  | PE_TX1_DR8_N | 2543.7399999999998 |  | 9589.8499999999985 |  | E10 | E10 | D85_PCIE_A_TX0_P | 1053.4100000000001 |  | 10643.259999999998 |  |  |  |  |  |  |  |  |  |  |  |
| PCIE_TX_CAP_P28 |  | 6541.08 | yes; within 1 mils | PCIE_TX_P28 | 505.2 | yes; within 1 mils | 7046.28 | yes; within 1 mils |  | PE_TX1_DR8_P | 2543.7399999999998 | yes; within 1 mils | 9590.02 | yes; within 5 mils | E11 | E11 | D85_PCIE_A_TX0_N | 1053.3499999999999 | yes; within 1 mils | 10643.37 | yes; within 5 mils |  |  |  |  |  |  |  |  |  |  |
| PCIE_TX_CAP_N29 |  | 6520.02 |  | PCIE_TX_N29 | 505.21 |  | 7025.2300000000005 |  |  | PE_TX2_DR8_N | 2171.15 |  | 9196.380000000001 |  | S17 | S17 | D85_PCIE_A_TX1_P | 1230.57 |  | 10426.950000000001 |  |  |  |  |  |  |  |  |  |  |  |
| PCIE_TX_CAP_P29 |  | 6520.08 | yes; within 1 mils | PCIE_TX_P29 | 505.21 | yes; within 1 mils | 7025.29 | yes; within 1 mils |  | PE_TX2_DR8_P | 2171.17 | yes; within 1 mils | 9196.4599999999991 | yes; within 5 mils | S18 | S18 | D85_PCIE_A_TX1_N | 1230.52 | yes; within 1 mils | 10426.98 | yes; within 5 mils |  |  |  |  |  |  |  |  |  |  |
|  |  |  |  |  |  | routing bundle delta | 21.049999999999272 |  |  | routing bundle delta | 372.58999999999969 | routing bundle delta | 393.63999999999942 | yes; within 600mil |  |  | routing bundle delta | 177.22000000000003 | routing bundle delta | 216.42000000000007 |  |  |  |  |  |  |  |  |  |  |  |
| PCIE_TX_CAP_N30 |  | 6379.73 |  | PCIE_TX_N30 | 505.21 |  | 6884.94 |  |  | PE_TX3_DR8_N | 2142.13 |  | 9027.07 |  | S23 | S23 | D85_PCIE_B_TX0_P | 505.9 |  | 9532.9699999999993 |  |  |  |  |  |  |  |  |  |  |  |
| PCIE_TX_CAP_P30 |  | 6380.2 | yes; within 1 mils | PCIE_TX_P30 | 505.21 | yes; within 1 mils | 6885.41 | yes; within 1 mils |  | PE_TX3_DR8_P | 2142.14 | yes; within 1 mils | 9027.5499999999993 | yes; within 5 mils | S24 | S24 | D85_PCIE_B_TX0_N | 505.9 | yes; within 1 mils | 9533.4499999999989 | yes; within 5 mils |  |  |  |  |  |  |  |  |  |  |
| PCIE_TX_CAP_N31 |  | 6329.62 |  | PCIE_TX_N31 | 505.21 |  | 6834.83 |  |  | PE_TX4_DR8_N | 2121.09 |  | 8955.92 |  | E17 | E17 | D85_PCIE_B_TX1_P | 536.89 |  | 9492.81 |  |  |  |  |  |  |  |  |  |  |  |
| PCIE_TX_CAP_P31 |  | 6329.82 | yes; within 1 mils | PCIE_TX_P31 | 505.2 | yes; within 1 mils | 6835.0199999999995 | yes; within 1 mils |  | PE_TX4_DR8_P | 2121.09 | yes; within 1 mils | 8956.11 | yes; within 5 mils | E18 | E18 | D85_PCIE_B_TX1_N | 536.82000000000005 | yes; within 1 mils | 9492.93 | yes; within 5 mils |  |  |  |  |  |  |  |  |  |  |
|  |  |  |  |  |  | routing bundle delta | 50.579999999999927 |  |  | routing bundle delta | 21.049999999999727 | routing bundle delta | 71.6299999999992 | yes; within 600mil |  |  | routing bundle delta | 30.990000000000009 | routing bundle delta | 40.639999999999418 |  |  |  |  |  |  |  |  |  |  |  |
|  |  |  |  |  |  | diff pair to pair delta | 211.44999999999982 | yes; within 2000mil |  | diff pair to pair delta | 422.64999999999964 | yes; within 2000mil | 634.10000000000036 | yes; within 2000mil |  |  | diff pair to pair delta | 724.67 | yes; within 2000mil | 1150.5600000000013 | yes; within 2000mil |  |  |  |  |  |  |  |  |  |  |
| PM8536 to GF of PEB |  |  |  | Card Edge Connector | Connector of PDPB to U.2 Connector (J8) |  |  |  |  | SFF-8639 Conn | SFF-8639 Conn | M.2 Conn |  |  |  |  |  |  |  |  |  |  |  |  |  |  |  |  |  |  |  |
| Net Name | PKG Lengths | PCB Net Length | Differential Match | The Length of Connector | Net Name | PCB Net Length | Differential Match | Total Length | Differential Match | Pin of Connector | Pin of Connector | Net Name | PCB Net Length | Differential Match | Total Length | Differential Match |  |  |  |  |  |  |  |  |  |  |  |  |  |  |  |
| PCIE_RX_N28 |  | 7346.78 |  |  | PE_RX1_DR8_N | 2388.19 |  | 9734.9699999999993 |  | E13 | E13 | D85_PCIE_A_RX0_N | 1244.06 |  | 10979.029999999999 |  |  |  |  |  |  |  |  |  |  |  |  |  |  |  |  |
| PCIE_RX_P28 |  | 7346.38 | yes; within 1 mils |  | PE_RX1_DR8_P | 2388.17 | yes; within 1 mils | 9734.5499999999993 | yes; within 5 mils | E14 | E14 | D85_PCIE_A_RX0_P | 1244.6500000000001 | yes; within 1 mils | 10979.199999999999 | yes; within 5 mils |  |  |  |  |  |  |  |  |  |  |  |  |  |  |  |
| PCIE_RX_N29 |  | 7274.56 |  |  | PE_RX2_DR8_N | 2061.2600000000002 |  | 9335.82 |  | S20 | S20 | D85_PCIE_A_RX1_N | 1537.67 |  | 10873.49 |  |  |  |  |  |  |  |  |  |  |  |  |  |  |  |  |
| PCIE_RX_P29 |  | 7274.68 | yes; within 1 mils |  | PE_RX2_DR8_P | 2061.23 | yes; within 1 mils | 9335.91 | yes; within 5 mils | S21 | S21 | D85_PCIE_A_RX1_P | 1538.32 | yes; within 1 mils | 10874.23 | yes; within 5 mils |  |  |  |  |  |  |  |  |  |  |  |  |  |  |  |
|  | routing bundle delta | 72.219999999999345 |  |  | routing bundle delta | 326.96000000000004 | routing bundle delta | 399.14999999999964 | yes; within 600mil |  |  | routing bundle delta | 294.26 | routing bundle delta | 105.70999999999913 |  |  |  |  |  |  |  |  |  |  |  |  |  |  |  |  |
| PCIE_RX_N30 |  | 7133.65 |  |  | PE_RX3_DR8_N | 2036.12 |  | 9169.77 |  | S26 | S26 | D85_PCIE_B_RX0_N | 946.63 |  | 10116.4 |  |  |  |  |  |  |  |  |  |  |  |  |  |  |  |  |
| PCIE_RX_P30 |  | 7134.48 | yes; within 1 mils |  | PE_RX3_DR8_P | 2036.08 | yes; within 1 mils | 9170.56 | yes; within 5 mils | S27 | S27 | D85_PCIE_B_RX0_P | 947.24 | yes; within 1 mils | 10117.799999999999 | yes; within 5 mils |  |  |  |  |  |  |  |  |  |  |  |  |  |  |  |
| PCIE_RX_N31 |  | 7079.72 |  |  | PE_RX4_DR8_N | 2002.18 |  | 9081.9 |  | E20 | E20 | D85_PCIE_B_RX1_N | 955.34 |  | 10037.24 |  |  |  |  |  |  |  |  |  |  |  |  |  |  |  |  |
| PCIE_RX_P31 |  | 7079.45 | yes; within 1 mils |  | PE_RX4_DR8_P | 2002.05 | yes; within 1 mils | 9081.5 | yes; within 5 mils | E21 | E21 | D85_PCIE_B_RX1_P | 955.96 | yes; within 1 mils | 10037.459999999999 | yes; within 5 mils |  |  |  |  |  |  |  |  |  |  |  |  |  |  |  |
|  | routing bundle delta | 55.029999999999745 |  |  | routing bundle delta | 34.069999999999936 | routing bundle delta | 89.059999999999491 | yes; within 600mil |  |  | routing bundle delta | 9.3300000000000409 | routing bundle delta | 80.559999999999491 |  |  |  |  |  |  |  |  |  |  |  |  |  |  |  |  |
|  | diff pair to pair delta | 267.32999999999993 | yes; within 2000mil |  | diff pair to pair delta | 386.1400000000001 | yes; within 2000mil | 653.46999999999935 | yes; within 2000mil |  |  | diff pair to pair delta | 591.68999999999994 | yes; within 2000mil | 941.95999999999913 | yes; within 2000mil |  |  |  |  |  |  |  |  |  |  |  |  |  |  |  |
| PM8536 to SSD9 |  |  |  |  |  |  |  |  |  |  |  |  |  |  | PCISLT68-14-GP-U | SKT-SAS28-P15-PCIE25-2-GP |  |  |  |  |  |  |  |  |  |  |  |  |  |  |  |
| PM8536 to GF of PEB |  |  |  |  |  |  |  |  | Card Edge Connector | Connector of PDPB to U.2 Connector (J9) |  |  |  |  | SFF-8639 Conn | SFF-8639 Conn | M.2 Conn |  |  |  |  |  |  |  |  |  |  |  |  |  |  |
| Net Name | PKG Lengths | PCB Net Length | Differential Match | Net Name | PCB Net Length | Differential Match | PEB Total Length | Differential Match | The Length of Connector | Net Name | PCB Net Length | Differential Match | Total Length | Differential Match | Pin of Connector | Pin of Connector | Net Name | PCB Net Length | Differential Match | Total Length | Differential Match |  |  |  |  |  |  |  |  |  |  |
| PCIE_TX_CAP_N24 |  | 7069.27 |  | PCIE_TX_N24 | 505.21 |  | 7574.4800000000005 |  |  | PE_TX1_DR9_N | 6818.65 |  | 14393.130000000001 |  | E10 | E10 | D85_PCIE_A_TX0_P | 1053.4100000000001 |  | 15446.54 |  |  |  |  |  |  |  |  |  |  |  |
| PCIE_TX_CAP_P24 |  | 7069.43 | yes; within 1 mils | PCIE_TX_P24 | 505.21 | yes; within 1 mils | 7574.64 | yes; within 1 mils |  | PE_TX1_DR9_P | 6818.66 | yes; within 1 mils | 14393.3 | yes; within 5 mils | E11 | E11 | D85_PCIE_A_TX0_N | 1053.3499999999999 | yes; within 1 mils | 15446.65 | yes; within 5 mils |  |  |  |  |  |  |  |  |  |  |
| PCIE_TX_CAP_N25 |  | 7008.78 |  | PCIE_TX_N25 | 505.21 |  | 7513.99 |  |  | PE_TX2_DR9_N | 6464.39 |  | 13978.380000000001 |  | S17 | S17 | D85_PCIE_A_TX1_P | 1230.57 |  | 15208.95 |  |  |  |  |  |  |  |  |  |  |  |
| PCIE_TX_CAP_P25 |  | 7008.69 | yes; within 1 mils | PCIE_TX_P25 | 505.22 | yes; within 1 mils | 7513.91 | yes; within 1 mils |  | PE_TX2_DR9_P | 6464.39 | yes; within 1 mils | 13978.3 | yes; within 5 mils | S18 | S18 | D85_PCIE_A_TX1_N | 1230.52 | yes; within 1 mils | 15208.82 | yes; within 5 mils |  |  |  |  |  |  |  |  |  |  |
|  |  |  |  |  |  | routing bundle delta | 60.730000000000473 |  |  | routing bundle delta | 354.26999999999953 | routing bundle delta | 415 | yes; within 600mil |  |  | routing bundle delta | 177.22000000000003 | routing bundle delta | 237.82999999999993 |  |  |  |  |  |  |  |  |  |  |  |
| PCIE_TX_CAP_N26 |  | 6806.05 |  | PCIE_TX_N26 | 505.21 |  | 7311.26 |  |  | PE_TX3_DR9_N | 6514.93 |  | 13826.19 |  | S23 | S23 | D85_PCIE_B_TX0_P | 505.9 |  | 14332.09 |  |  |  |  |  |  |  |  |  |  |  |
| PCIE_TX_CAP_P26 |  | 6806.07 | yes; within 1 mils | PCIE_TX_P26 | 505.2 | yes; within 1 mils | 7311.2699999999995 | yes; within 1 mils |  | PE_TX3_DR9_P | 6514.93 | yes; within 1 mils | 13826.2 | yes; within 5 mils | S24 | S24 | D85_PCIE_B_TX0_N | 505.9 | yes; within 1 mils | 14332.1 | yes; within 5 mils |  |  |  |  |  |  |  |  |  |  |
| PCIE_TX_CAP_N27 |  | 6748.7 |  | PCIE_TX_N27 | 505.21 |  | 7253.91 |  |  | PE_TX4_DR9_N | 6487.35 |  | 13741.26 |  | E17 | E17 | D85_PCIE_B_TX1_P | 536.89 |  | 14278.15 |  |  |  |  |  |  |  |  |  |  |  |
| PCIE_TX_CAP_P27 |  | 6748.5 | yes; within 1 mils | PCIE_TX_P27 | 505.21 | yes; within 1 mils | 7253.71 | yes; within 1 mils |  | PE_TX4_DR9_P | 6487.28 | yes; within 1 mils | 13740.99 | yes; within 5 mils | E18 | E18 | D85_PCIE_B_TX1_N | 536.82000000000005 | yes; within 1 mils | 14277.81 | yes; within 5 mils |  |  |  |  |  |  |  |  |  |  |
|  |  |  |  |  |  | routing bundle delta | 57.559999999999491 |  |  | routing bundle delta | 27.650000000000546 | routing bundle delta | 85.210000000000946 | yes; within 600mil |  |  | routing bundle delta | 30.990000000000009 | routing bundle delta | 54.290000000000873 |  |  |  |  |  |  |  |  |  |  |  |
|  |  |  |  |  |  | diff pair to pair delta | 320.93000000000029 | yes; within 2000mil |  | diff pair to pair delta | 354.26999999999953 | yes; within 2000mil | 652.30999999999949 | yes; within 2000mil |  |  | diff pair to pair delta | 724.67 | yes; within 2000mil | 1168.8400000000001 | yes; within 2000mil |  |  |  |  |  |  |  |  |  |  |
| PM8536 to GF of PEB |  |  |  | Card Edge Connector | Connector of PDPB to U.2 Connector (J9) |  |  |  |  | SFF-8639 Conn | SFF-8639 Conn | M.2 Conn |  |  |  |  |  |  |  |  |  |  |  |  |  |  |  |  |  |  |  |
| Net Name | PKG Lengths | PCB Net Length | Differential Match | The Length of Connector | Net Name | PCB Net Length | Differential Match | Total Length | Differential Match | Pin of Connector | Pin of Connector | Net Name | PCB Net Length | Differential Match | Total Length | Differential Match |  |  |  |  |  |  |  |  |  |  |  |  |  |  |  |
| PCIE_RX_N24 |  | 7783.6 |  |  | PE_RX1_DR9_N | 6704.35 |  | 14487.95 |  | E13 | E13 | D85_PCIE_A_RX0_N | 1244.06 |  | 15732.01 |  |  |  |  |  |  |  |  |  |  |  |  |  |  |  |  |
| PCIE_RX_P24 |  | 7784.31 | yes; within 1 mils |  | PE_RX1_DR9_P | 6704.35 | yes; within 1 mils | 14488.66 | yes; within 5 mils | E14 | E14 | D85_PCIE_A_RX0_P | 1244.6500000000001 | yes; within 1 mils | 15733.31 | yes; within 5 mils |  |  |  |  |  |  |  |  |  |  |  |  |  |  |  |
| PCIE_RX_N25 |  | 7688.41 |  |  | PE_RX2_DR9_N | 6387.53 |  | 14075.939999999999 |  | S20 | S20 | D85_PCIE_A_RX1_N | 1537.67 |  | 15613.609999999999 |  |  |  |  |  |  |  |  |  |  |  |  |  |  |  |  |
| PCIE_RX_P25 |  | 7687.99 | yes; within 1 mils |  | PE_RX2_DR9_P | 6387.51 | yes; within 1 mils | 14075.5 | yes; within 5 mils | S21 | S21 | D85_PCIE_A_RX1_P | 1538.32 | yes; within 1 mils | 15613.82 | yes; within 5 mils |  |  |  |  |  |  |  |  |  |  |  |  |  |  |  |
|  | routing bundle delta | 96.320000000000618 |  |  | routing bundle delta | 316.84000000000015 | routing bundle delta | 413.15999999999985 | yes; within 600mil |  |  | routing bundle delta | 294.26 | routing bundle delta | 119.70000000000073 |  |  |  |  |  |  |  |  |  |  |  |  |  |  |  |  |
| PCIE_RX_N26 |  | 7524.42 |  |  | PE_RX3_DR9_N | 6418.17 |  | 13942.59 |  | S26 | S26 | D85_PCIE_B_RX0_N | 946.63 |  | 14889.22 |  |  |  |  |  |  |  |  |  |  |  |  |  |  |  |  |
| PCIE_RX_P26 |  | 7523.97 | yes; within 1 mils |  | PE_RX3_DR9_P | 6418.43 | yes; within 1 mils | 13942.400000000001 | yes; within 5 mils | S27 | S27 | D85_PCIE_B_RX0_P | 947.24 | yes; within 1 mils | 14889.640000000001 | yes; within 5 mils |  |  |  |  |  |  |  |  |  |  |  |  |  |  |  |
| PCIE_RX_N27 |  | 7465.37 |  |  | PE_RX4_DR9_N | 6379.88 |  | 13845.25 |  | E20 | E20 | D85_PCIE_B_RX1_N | 955.34 |  | 14800.59 |  |  |  |  |  |  |  |  |  |  |  |  |  |  |  |  |
| PCIE_RX_P27 |  | 7464.53 | yes; within 1 mils |  | PE_RX4_DR9_P | 6380.04 | yes; within 1 mils | 13844.57 | yes; within 5 mils | E21 | E21 | D85_PCIE_B_RX1_P | 955.96 | yes; within 1 mils | 14800.529999999999 | yes; within 5 mils |  |  |  |  |  |  |  |  |  |  |  |  |  |  |  |
|  | routing bundle delta | 59.890000000000327 |  |  | routing bundle delta | 38.550000000000182 | routing bundle delta | 98.020000000000437 | yes; within 600mil |  |  | routing bundle delta | 9.3300000000000409 | routing bundle delta | 89.110000000002401 |  |  |  |  |  |  |  |  |  |  |  |  |  |  |  |  |
|  | diff pair to pair delta | 319.78000000000065 | yes; within 2000mil |  | diff pair to pair delta | 324.47000000000025 | yes; within 2000mil | 644.09000000000015 | yes; within 2000mil |  |  | diff pair to pair delta | 591.68999999999994 | yes; within 2000mil | 932.78000000000065 | yes; within 2000mil |  |  |  |  |  |  |  |  |  |  |  |  |  |  |  |
| PM8536 to SSD13 |  |  |  |  |  |  |  |  |  |  |  |  |  |  | PCISLT68-14-GP-U | SKT-SAS28-P15-PCIE25-2-GP |  |  |  |  |  |  |  |  |  |  |  |  |  |  |  |
| PM8536 to GF of PEB |  |  |  |  |  |  |  |  | Card Edge Connector | Connector of PDPB to U.2 Connector (J13) |  |  |  |  | SFF-8639 Conn | SFF-8639 Conn | M.2 Conn |  |  |  |  |  |  |  |  |  |  |  |  |  |  |
| Net Name | PKG Lengths | PCB Net Length | Differential Match | Net Name | PCB Net Length | Differential Match | PEB Total Length | Differential Match | The Length of Connector | Net Name | PCB Net Length | Differential Match | Total Length | Differential Match | Pin of Connector | Pin of Connector | Net Name | PCB Net Length | Differential Match | Total Length | Differential Match |  |  |  |  |  |  |  |  |  |  |
| PCIE_TX_CAP_N20 |  | 7520.01 |  | PCIE_TX_N20 | 505.21 |  | 8025.22 |  |  | PE_TX1_DR13_N | 2074.4499999999998 |  | 10099.67 |  | E10 | E10 | D85_PCIE_A_TX0_P | 1053.4100000000001 |  | 11153.08 |  |  |  |  |  |  |  |  |  |  |  |
| PCIE_TX_CAP_P20 |  | 7519.48 | yes; within 1 mils | PCIE_TX_P20 | 505.2 | yes; within 1 mils | 8024.6799999999994 | yes; within 1 mils |  | PE_TX1_DR13_P | 2074.4899999999998 | yes; within 1 mils | 10099.169999999998 | yes; within 5 mils | E11 | E11 | D85_PCIE_A_TX0_N | 1053.3499999999999 | yes; within 1 mils | 11152.519999999999 | yes; within 5 mils |  |  |  |  |  |  |  |  |  |  |
| PCIE_TX_CAP_N21 |  | 7457.03 |  | PCIE_TX_N21 | 505.21 |  | 7962.24 |  |  | PE_TX2_DR13_N | 2721.55 |  | 10683.79 |  | S17 | S17 | D85_PCIE_A_TX1_P | 1230.57 |  | 11914.36 |  |  |  |  |  |  |  |  |  |  |  |
| PCIE_TX_CAP_P21 |  | 7457 | yes; within 1 mils | PCIE_TX_P21 | 505.21 | yes; within 1 mils | 7962.21 | yes; within 1 mils |  | PE_TX2_DR13_P | 2721.58 | yes; within 1 mils | 10683.79 | yes; within 5 mils | S18 | S18 | D85_PCIE_A_TX1_N | 1230.52 | yes; within 1 mils | 11914.310000000001 | yes; within 5 mils |  |  |  |  |  |  |  |  |  |  |
|  |  |  |  |  |  | routing bundle delta | 63.010000000000218 |  |  | routing bundle delta | 647.13000000000011 | routing bundle delta | 584.62000000000262 | yes; within 600mil |  |  | routing bundle delta | 177.22000000000003 | routing bundle delta | 761.84000000000196 |  |  |  |  |  |  |  |  |  |  |  |
| PCIE_TX_CAP_N22 |  | 7352.37 |  | PCIE_TX_N22 | 505.21 |  | 7857.58 |  |  | PE_TX3_DR13_N | 3089.45 |  | 10947.029999999999 |  | S23 | S23 | D85_PCIE_B_TX0_P | 505.9 |  | 11452.929999999998 |  |  |  |  |  |  |  |  |  |  |  |
| PCIE_TX_CAP_P22 |  | 7352.52 | yes; within 1 mils | PCIE_TX_P22 | 505.21 | yes; within 1 mils | 7857.7300000000005 | yes; within 1 mils |  | PE_TX3_DR13_P | 3089.47 | yes; within 1 mils | 10947.2 | yes; within 5 mils | S24 | S24 | D85_PCIE_B_TX0_N | 505.9 | yes; within 1 mils | 11453.1 | yes; within 5 mils |  |  |  |  |  |  |  |  |  |  |
| PCIE_TX_CAP_N23 |  | 7254.19 |  | PCIE_TX_N23 | 505.21 |  | 7759.4 |  |  | PE_TX4_DR13_N | 3443.56 |  | 11202.96 |  | E17 | E17 | D85_PCIE_B_TX1_P | 536.89 |  | 11739.849999999999 |  |  |  |  |  |  |  |  |  |  |  |
| PCIE_TX_CAP_P23 |  | 7253.69 | yes; within 1 mils | PCIE_TX_P23 | 505.22 | yes; within 1 mils | 7758.91 | yes; within 1 mils |  | PE_TX4_DR13_P | 3443.49 | yes; within 1 mils | 11202.4 | yes; within 5 mils | E18 | E18 | D85_PCIE_B_TX1_N | 536.82000000000005 | yes; within 1 mils | 11739.22 | yes; within 5 mils |  |  |  |  |  |  |  |  |  |  |
|  |  |  |  |  |  | routing bundle delta | 98.820000000000618 |  |  | routing bundle delta | 354.11000000000013 | routing bundle delta | 255.93000000000029 | yes; within 600mil |  |  | routing bundle delta | 30.990000000000009 | routing bundle delta | 286.92000000000007 |  |  |  |  |  |  |  |  |  |  |  |
|  |  |  |  |  |  | diff pair to pair delta | 266.3100000000004 | yes; within 2000mil |  | diff pair to pair delta | 1369.1100000000001 | yes; within 2000mil | 1103.7900000000009 | yes; within 2000mil |  |  | diff pair to pair delta | 724.67 | yes; within 2000mil | 761.84000000000196 | yes; within 2000mil |  |  |  |  |  |  |  |  |  |  |
| PM8536 to GF of PEB |  |  |  | Card Edge Connector | Connector of PDPB to U.2 Connector (J13) |  |  |  |  | SFF-8639 Conn | SFF-8639 Conn | M.2 Conn |  |  |  |  |  |  |  |  |  |  |  |  |  |  |  |  |  |  |  |
| Net Name | PKG Lengths | PCB Net Length | Differential Match | The Length of Connector | Net Name | PCB Net Length | Differential Match | Total Length | Differential Match | Pin of Connector | Pin of Connector | Net Name | PCB Net Length | Differential Match | Total Length | Differential Match |  |  |  |  |  |  |  |  |  |  |  |  |  |  |  |
| PCIE_RX_N20 |  | 8219.74 |  |  | PE_RX1_DR13_N | 2600.88 |  | 10820.619999999999 |  | E13 | E13 | D85_PCIE_A_RX0_N | 1244.06 |  | 12064.679999999998 |  |  |  |  |  |  |  |  |  |  |  |  |  |  |  |  |
| PCIE_RX_P20 |  | 8220.6 | yes; within 1 mils |  | PE_RX1_DR13_P | 2600.6 | yes; within 1 mils | 10821.2 | yes; within 5 mils | E14 | E14 | D85_PCIE_A_RX0_P | 1244.6500000000001 | yes; within 1 mils | 12065.85 | yes; within 5 mils |  |  |  |  |  |  |  |  |  |  |  |  |  |  |  |
| PCIE_RX_N21 |  | 8118.93 |  |  | PE_RX2_DR13_N | 2889.56 |  | 11008.49 |  | S20 | S20 | D85_PCIE_A_RX1_N | 1537.67 |  | 12546.16 |  |  |  |  |  |  |  |  |  |  |  |  |  |  |  |  |
| PCIE_RX_P21 |  | 8118.41 | yes; within 1 mils |  | PE_RX2_DR13_P | 2890.27 | yes; within 1 mils | 11008.68 | yes; within 5 mils | S21 | S21 | D85_PCIE_A_RX1_P | 1538.32 | yes; within 1 mils | 12547 | yes; within 5 mils |  |  |  |  |  |  |  |  |  |  |  |  |  |  |  |
|  | routing bundle delta | 102.19000000000051 |  |  | routing bundle delta | 289.67000000000007 | routing bundle delta | 188.06000000000131 | yes; within 600mil |  |  | routing bundle delta | 294.26 | routing bundle delta | 482.32000000000153 |  |  |  |  |  |  |  |  |  |  |  |  |  |  |  |  |
| PCIE_RX_N22 |  | 7982.56 |  |  | PE_RX3_DR13_N | 3194.59 |  | 11177.150000000001 |  | S26 | S26 | D85_PCIE_B_RX0_N | 946.63 |  | 12123.78 |  |  |  |  |  |  |  |  |  |  |  |  |  |  |  |  |
| PCIE_RX_P22 |  | 7982.54 | yes; within 1 mils |  | PE_RX3_DR13_P | 3195.06 | yes; within 1 mils | 11177.6 | yes; within 5 mils | S27 | S27 | D85_PCIE_B_RX0_P | 947.24 | yes; within 1 mils | 12124.84 | yes; within 5 mils |  |  |  |  |  |  |  |  |  |  |  |  |  |  |  |
| PCIE_RX_N23 |  | 7922.3 |  |  | PE_RX4_DR13_N | 3489.03 |  | 11411.33 |  | E20 | E20 | D85_PCIE_B_RX1_N | 955.34 |  | 12366.67 |  |  |  |  |  |  |  |  |  |  |  |  |  |  |  |  |
| PCIE_RX_P23 |  | 7921.95 | yes; within 1 mils |  | PE_RX4_DR13_P | 3489.49 | yes; within 1 mils | 11411.439999999999 | yes; within 5 mils | E21 | E21 | D85_PCIE_B_RX1_P | 955.96 | yes; within 1 mils | 12367.399999999998 | yes; within 5 mils |  |  |  |  |  |  |  |  |  |  |  |  |  |  |  |
|  | routing bundle delta | 60.610000000000582 |  |  | routing bundle delta | 294.89999999999964 | routing bundle delta | 234.28999999999724 | yes; within 600mil |  |  | routing bundle delta | 9.3300000000000409 | routing bundle delta | 243.61999999999716 |  |  |  |  |  |  |  |  |  |  |  |  |  |  |  |  |
|  | diff pair to pair delta | 298.65000000000055 | yes; within 2000mil |  | diff pair to pair delta | 888.88999999999987 | yes; within 2000mil | 590.81999999999971 | yes; within 2000mil |  |  | diff pair to pair delta | 591.68999999999994 | yes; within 2000mil | 482.32000000000153 | yes; within 2000mil |  |  |  |  |  |  |  |  |  |  |  |  |  |  |  |
| PM8536 to SSD14 |  |  |  |  |  |  |  |  |  |  |  |  |  |  | PCISLT68-14-GP-U | SKT-SAS28-P15-PCIE25-2-GP |  |  |  |  |  |  |  |  |  |  |  |  |  |  |  |
| PM8536 to GF of PEB |  |  |  |  |  |  |  |  | Card Edge Connector | Connector of PDPB to U.2 Connector (J14) |  |  |  |  | SFF-8639 Conn | SFF-8639 Conn | M.2 Conn |  |  |  |  |  |  |  |  |  |  |  |  |  |  |
| Net Name | PKG Lengths | PCB Net Length | Differential Match | Net Name | PCB Net Length | Differential Match | PEB Total Length | Differential Match | The Length of Connector | Net Name | PCB Net Length | Differential Match | Total Length | Differential Match | Pin of Connector | Pin of Connector | Net Name | PCB Net Length | Differential Match | Total Length | Differential Match |  |  |  |  |  |  |  |  |  |  |
| PCIE_TX_CAP_N16 |  | 7918.96 |  | PCIE_TX_N16 | 505.21 |  | 8424.17 |  |  | PE_TX1_DR14_N | 5307.64 |  | 13731.810000000001 |  | E10 | E10 | D85_PCIE_A_TX0_P | 1053.4100000000001 |  | 14785.220000000001 |  |  |  |  |  |  |  |  |  |  |  |
| PCIE_TX_CAP_P16 |  | 7918.99 | yes; within 1 mils | PCIE_TX_P16 | 505.2 | yes; within 1 mils | 8424.19 | yes; within 1 mils |  | PE_TX1_DR14_P | 5307.54 | yes; within 1 mils | 13731.73 | yes; within 5 mils | E11 | E11 | D85_PCIE_A_TX0_N | 1053.3499999999999 | yes; within 1 mils | 14785.08 | yes; within 5 mils |  |  |  |  |  |  |  |  |  |  |
| PCIE_TX_CAP_N17 |  | 7878.84 |  | PCIE_TX_N17 | 505.21 |  | 8384.0499999999993 |  |  | PE_TX2_DR14_N | 6012.78 |  | 14396.829999999998 |  | S17 | S17 | D85_PCIE_A_TX1_P | 1230.57 |  | 15627.399999999998 |  |  |  |  |  |  |  |  |  |  |  |
| PCIE_TX_CAP_P17 |  | 7878.65 | yes; within 1 mils | PCIE_TX_P17 | 505.21 | yes; within 1 mils | 8383.8599999999988 | yes; within 1 mils |  | PE_TX2_DR14_P | 6013.23 | yes; within 1 mils | 14397.089999999998 | yes; within 5 mils | S18 | S18 | D85_PCIE_A_TX1_N | 1230.52 | yes; within 1 mils | 15627.609999999999 | yes; within 5 mils |  |  |  |  |  |  |  |  |  |  |
|  |  |  |  |  |  | routing bundle delta | 40.330000000001746 |  |  | routing bundle delta | 705.6899999999996 | routing bundle delta | 665.35999999999876 | no; exceed 600mil |  |  | routing bundle delta | 177.22000000000003 | routing bundle delta | 842.52999999999884 |  |  |  |  |  |  |  |  |  |  |  |
| PCIE_TX_CAP_N18 |  | 7743.67 |  | PCIE_TX_N18 | 505.21 |  | 8248.8799999999992 |  |  | PE_TX3_DR14_N | 6317.21 |  | 14566.09 |  | S23 | S23 | D85_PCIE_B_TX0_P | 505.9 |  | 15071.99 |  |  |  |  |  |  |  |  |  |  |  |
| PCIE_TX_CAP_P18 |  | 7743.82 | yes; within 1 mils | PCIE_TX_P18 | 505.21 | yes; within 1 mils | 8249.0299999999988 | yes; within 1 mils |  | PE_TX3_DR14_P | 6317.11 | yes; within 1 mils | 14566.14 | yes; within 5 mils | S24 | S24 | D85_PCIE_B_TX0_N | 505.9 | yes; within 1 mils | 15072.039999999999 | yes; within 5 mils |  |  |  |  |  |  |  |  |  |  |
| PCIE_TX_CAP_N19 |  | 7709.83 |  | PCIE_TX_N19 | 505.21 |  | 8215.0399999999991 |  |  | PE_TX4_DR14_N | 6664.18 |  | 14879.22 |  | E17 | E17 | D85_PCIE_B_TX1_P | 536.89 |  | 15416.109999999999 |  |  |  |  |  |  |  |  |  |  |  |
| PCIE_TX_CAP_P19 |  | 7709.85 | yes; within 1 mils | PCIE_TX_P19 | 505.22 | yes; within 1 mils | 8215.07 | yes; within 1 mils |  | PE_TX4_DR14_P | 6664.19 | yes; within 1 mils | 14879.259999999998 | yes; within 5 mils | E18 | E18 | D85_PCIE_B_TX1_N | 536.82000000000005 | yes; within 1 mils | 15416.079999999998 | yes; within 5 mils |  |  |  |  |  |  |  |  |  |  |
|  |  |  |  |  |  | routing bundle delta | 33.989999999999782 |  |  | routing bundle delta | 347.07999999999993 | routing bundle delta | 313.16999999999825 | yes; within 600mil |  |  | routing bundle delta | 30.990000000000009 | routing bundle delta | 344.11999999999898 |  |  |  |  |  |  |  |  |  |  |  |
|  |  |  |  |  |  | diff pair to pair delta | 209.15000000000146 | yes; within 2000mil |  | diff pair to pair delta | 1356.6499999999996 | yes; within 2000mil | 1147.5299999999988 | yes; within 2000mil |  |  | diff pair to pair delta | 724.67 | yes; within 2000mil | 842.52999999999884 | yes; within 2000mil |  |  |  |  |  |  |  |  |  |  |
| PM8536 to GF of PEB |  |  |  | Card Edge Connector | Connector of PDPB to U.2 Connector (J14) |  |  |  |  | SFF-8639 Conn | SFF-8639 Conn | M.2 Conn |  |  |  |  |  |  |  |  |  |  |  |  |  |  |  |  |  |  |  |
| Net Name | PKG Lengths | PCB Net Length | Differential Match | The Length of Connector | Net Name | PCB Net Length | Differential Match | Total Length | Differential Match | Pin of Connector | Pin of Connector | Net Name | PCB Net Length | Differential Match | Total Length | Differential Match |  |  |  |  |  |  |  |  |  |  |  |  |  |  |  |
| PCIE_RX_N16 |  | 8640.8700000000008 |  |  | PE_RX1_DR14_N | 5517.26 |  | 14158.130000000001 |  | E13 | E13 | D85_PCIE_A_RX0_N | 1244.06 |  | 15402.19 |  |  |  |  |  |  |  |  |  |  |  |  |  |  |  |  |
| PCIE_RX_P16 |  | 8640.84 | yes; within 1 mils |  | PE_RX1_DR14_P | 5517.79 | yes; within 1 mils | 14158.630000000001 | yes; within 5 mils | E14 | E14 | D85_PCIE_A_RX0_P | 1244.6500000000001 | yes; within 1 mils | 15403.28 | yes; within 5 mils |  |  |  |  |  |  |  |  |  |  |  |  |  |  |  |
| PCIE_RX_N17 |  | 8575.94 |  |  | PE_RX2_DR14_N | 6084.91 |  | 14660.85 |  | S20 | S20 | D85_PCIE_A_RX1_N | 1537.67 |  | 16198.52 |  |  |  |  |  |  |  |  |  |  |  |  |  |  |  |  |
| PCIE_RX_P17 |  | 8575.36 | yes; within 1 mils |  | PE_RX2_DR14_P | 6085.23 | yes; within 1 mils | 14660.59 | yes; within 5 mils | S21 | S21 | D85_PCIE_A_RX1_P | 1538.32 | yes; within 1 mils | 16198.91 | yes; within 5 mils |  |  |  |  |  |  |  |  |  |  |  |  |  |  |  |
|  | routing bundle delta | 65.510000000000218 |  |  | routing bundle delta | 567.96999999999935 | routing bundle delta | 502.71999999999935 | yes; within 600mil |  |  | routing bundle delta | 294.26 | routing bundle delta | 796.71999999999935 |  |  |  |  |  |  |  |  |  |  |  |  |  |  |  |  |
| PCIE_RX_N18 |  | 8405.51 |  |  | PE_RX3_DR14_N | 6470.1 |  | 14875.61 |  | S26 | S26 | D85_PCIE_B_RX0_N | 946.63 |  | 15822.24 |  |  |  |  |  |  |  |  |  |  |  |  |  |  |  |  |
| PCIE_RX_P18 |  | 8405.48 | yes; within 1 mils |  | PE_RX3_DR14_P | 6469.99 | yes; within 1 mils | 14875.47 | yes; within 5 mils | S27 | S27 | D85_PCIE_B_RX0_P | 947.24 | yes; within 1 mils | 15822.71 | yes; within 5 mils |  |  |  |  |  |  |  |  |  |  |  |  |  |  |  |
| PCIE_RX_N19 |  | 8345.36 |  |  | PE_RX4_DR14_N | 6775.55 |  | 15120.91 |  | E20 | E20 | D85_PCIE_B_RX1_N | 955.34 |  | 16076.25 |  |  |  |  |  |  |  |  |  |  |  |  |  |  |  |  |
| PCIE_RX_P19 |  | 8345.26 | yes; within 1 mils |  | PE_RX4_DR14_P | 6775.84 | yes; within 1 mils | 15121.1 | yes; within 5 mils | E21 | E21 | D85_PCIE_B_RX1_P | 955.96 | yes; within 1 mils | 16077.060000000001 | yes; within 5 mils |  |  |  |  |  |  |  |  |  |  |  |  |  |  |  |
|  | routing bundle delta | 60.25 |  |  | routing bundle delta | 305.85000000000036 | routing bundle delta | 245.63000000000102 | yes; within 600mil |  |  | routing bundle delta | 9.3300000000000409 | routing bundle delta | 254.82000000000153 |  |  |  |  |  |  |  |  |  |  |  |  |  |  |  |  |
|  | diff pair to pair delta | 295.61000000000058 | yes; within 2000mil |  | diff pair to pair delta | 1258.58 | yes; within 2000mil | 962.96999999999935 | yes; within 2000mil |  |  | diff pair to pair delta | 591.68999999999994 | yes; within 2000mil | 796.71999999999935 | yes; within 2000mil |  |  |  |  |  |  |  |  |  |  |  |  |  |  |  |
| PM8536 to BMC |  |  |  |  |  |  |  |  |  |  |  |  |  |  |  |  |  |  |  |  |  |  |  |  |  |  |  |  |  |  |  |
| PM8536 to BMC |  |  |  |  |  |  |  |  |  |  |  |  |  |  |  |  |  |  |  |  |  |  |  |  |  |  |  |  |  |  |  |
| Net Name | PKG Lengths | PCB Net Length | Differential Match | Net Name | PCB Net Length | Differential Match | PEB Total Length | Differential Match |  |  |  |  |  |  |  |  |  |  |  |  |  |  |  |  |  |  |  |  |  |  |  |
| PCIE_TX_CAP_N76 |  | 10420.68 |  | PCIE_TX_N76 | 327.33 |  | 10748.01 |  |  |  |  |  |  |  |  |  |  |  |  |  |  |  |  |  |  |  |  |  |  |  |  |
| PCIE_TX_CAP_P76 |  | 10420.25 | yes; within 1 mils | PCIE_TX_P76 | 327.38 | yes; within 1 mils | 10747.63 | yes; within 1 mils |  |  |  |  |  |  |  |  |  |  |  |  |  |  |  |  |  |  |  |  |  |  |  |
| PCIE_RX_N76 |  | 666.91 |  | BMC_PETXN | 10042.32 |  | 10709.23 |  |  |  |  |  |  |  |  |  |  |  |  |  |  |  |  |  |  |  |  |  |  |  |  |
| PCIE_RX_P76 |  | 666.85 | yes; within 1 mils | BMC_PETXP | 10042.52 | yes; within 1 mils | 10709.37 | yes; within 1 mils |  |  |  |  |  |  |  |  |  |  |  |  |  |  |  |  |  |  |  |  |  |  |  |
| PM8536 to I210 |  |  |  |  |  |  |  |  |  |  |  |  |  |  |  |  |  |  |  |  |  |  |  |  |  |  |  |  |  |  |  |
| PM8536 to I210 |  |  |  |  |  |  |  |  |  |  |  |  |  |  |  |  |  |  |  |  |  |  |  |  |  |  |  |  |  |  |  |
| Net Name | PKG Lengths | PCB Net Length | Differential Match | Net Name | PCB Net Length | Differential Match | PEB Total Length | Differential Match |  |  |  |  |  |  |  |  |  |  |  |  |  |  |  |  |  |  |  |  |  |  |  |
| PCIE_TX_CAP_N78 |  | 520.16 |  | PCIE_TX_N78 | 9066.85 |  | 9587.01 |  |  |  |  |  |  |  |  |  |  |  |  |  |  |  |  |  |  |  |  |  |  |  |  |
| PCIE_TX_CAP_P78 |  | 520.32000000000005 | yes; within 1 mils | PCIE_TX_P78 | 9067.34 | yes; within 1 mils | 9587.66 | yes; within 1 mils |  |  |  |  |  |  |  |  |  |  |  |  |  |  |  |  |  |  |  |  |  |  |  |
| PCIE_RX_N78 |  | 10259.31 |  | PCIE_RX_CAP_N78 | 150.78 |  | 10410.09 |  |  |  |  |  |  |  |  |  |  |  |  |  |  |  |  |  |  |  |  |  |  |  |  |
| PCIE_RX_P78 |  | 10260.1 | yes; within 1 mils | PCIE_RX_CAP_P78 | 150.25 | yes; within 1 mils | 10410.35 | yes; within 1 mils |  |  |  |  |  |  |  |  |  |  |  |  |  |  |  |  |  |  |  |  |  |  |  |
|  |  |  |  |  |  | The lane is AC-coupled between its corresponding transmitter and receiver. The AC-coupling capacitor |  |  |  |  |  |  |  |  |  |  |  |  |  |  |  |  |  |  |  |  |  |  |  |  |  |
|  |  |  |  |  |  | is located on the board close to transmitter side. Each end of the link is terminated on the die into |  |  |  |  |  |  |  |  |  |  |  |  |  |  |  |  |  |  |  |  |  |  |  |  |  |
|  |  |  |  |  |  | nominal 100 Ω differential DC impedance. Board termination is not required. |  |  |  |  |  |  |  |  |  |  |  |  |  |  |  |  |  |  |  |  |  |  |  |  |  |
